%FSTAX25Y25*%
%MOIN*%
%SFA1B1*%

%IPPOS*%
%ADD140C,0.120000*%
%ADD155C,0.075000*%
%ADD156C,0.098430*%
%ADD158O,0.177170X0.088580*%
%ADD159O,0.088580X0.177170*%
%ADD165C,0.016000*%
%LNgrandmaster-1*%
%LPD*%
G36*
X13389Y05513D02*
X09105D01*
Y0522933*
X08285*
Y05318*
X08253Y0535*
X08225*
X08193Y05318*
Y0522933*
X07772*
Y0534515*
X0777459Y0534649*
X07777Y0534711*
X0778176Y0534393*
X07788Y0534269*
X0779424Y0534393*
X0779953Y0534747*
X0780307Y0535276*
X0780431Y05359*
X0780307Y0536524*
X0779953Y0537053*
X0779424Y0537407*
X07788Y0537531*
X0778176Y0537407*
X07777Y0537089*
X0777459Y0537151*
X07772Y0537285*
Y05473*
X07726Y05519*
X07654*
X07609Y05474*
Y0531788*
X07312*
Y05516*
X06572*
Y05192*
X05998*
Y09358*
X06001Y09361*
X13389*
Y05513*
G37*
%LNgrandmaster-2*%
%LPC*%
G36*
X08561Y0930331D02*
X0855476Y0930207D01*
X0854947Y0929854*
X0854593Y0929324*
X0854469Y09287*
X0854593Y0928076*
X0854947Y0927547*
X0855476Y0927193*
X08561Y0927069*
X0856724Y0927193*
X0857253Y0927547*
X0857607Y0928076*
X0857731Y09287*
X0857607Y0929324*
X0857253Y0929854*
X0856724Y0930207*
X08561Y0930331*
G37*
G36*
X07285Y0927631D02*
X0727876Y0927507D01*
X0727347Y0927153*
X0726993Y0926624*
X0726869Y0926*
X0726993Y0925376*
X0727347Y0924846*
X0727876Y0924493*
X07285Y0924369*
X0729124Y0924493*
X0729654Y0924846*
X0730007Y0925376*
X0730131Y0926*
X0730007Y0926624*
X0729654Y0927153*
X0729124Y0927507*
X07285Y0927631*
G37*
G36*
X074645Y092995D02*
X073935D01*
Y092285*
X074645*
Y092995*
G37*
G36*
X080655Y092915D02*
X079945D01*
Y092205*
X080655*
Y092915*
G37*
G36*
X07548Y0924931D02*
X0754176Y0924807D01*
X0753647Y0924454*
X0753293Y0923924*
X0753169Y09233*
X0753293Y0922676*
X0753647Y0922147*
X0754176Y0921793*
X07548Y0921669*
X0755424Y0921793*
X0755954Y0922147*
X0756307Y0922676*
X0756431Y09233*
X0756307Y0923924*
X0755954Y0924454*
X0755424Y0924807*
X07548Y0924931*
G37*
G36*
X0777Y0917631D02*
X0776376Y0917507D01*
X0775846Y0917153*
X0775493Y0916624*
X0775369Y0916*
X0775493Y0915376*
X0775846Y0914847*
X0776376Y0914493*
X0777Y0914369*
X0777624Y0914493*
X0778154Y0914847*
X0778507Y0915376*
X0778631Y0916*
X0778507Y0916624*
X0778154Y0917153*
X0777624Y0917507*
X0777Y0917631*
G37*
G36*
X07429Y0919981D02*
X0741973Y0919859D01*
X074111Y0919501*
X0740368Y0918932*
X0739799Y091819*
X0739441Y0917327*
X0739319Y09164*
X0739441Y0915473*
X0739799Y091461*
X0740368Y0913868*
X074111Y0913299*
X0741973Y0912941*
X07429Y0912819*
X0743827Y0912941*
X074469Y0913299*
X0745432Y0913868*
X0746001Y091461*
X0746359Y0915473*
X0746481Y09164*
X0746359Y0917327*
X0746001Y091819*
X0745432Y0918932*
X074469Y0919501*
X0743827Y0919859*
X07429Y0919981*
G37*
G36*
X0803Y0919181D02*
X0802073Y0919059D01*
X080121Y0918701*
X0800468Y0918132*
X0799899Y091739*
X0799541Y0916527*
X0799419Y09156*
X0799541Y0914673*
X0799899Y091381*
X0800468Y0913068*
X080121Y0912499*
X0802073Y0912141*
X0803Y0912019*
X0803927Y0912141*
X080479Y0912499*
X0805532Y0913068*
X0806101Y091381*
X0806459Y0914673*
X0806581Y09156*
X0806459Y0916527*
X0806101Y091739*
X0805532Y0918132*
X080479Y0918701*
X0803927Y0919059*
X0803Y0919181*
G37*
G36*
X07576Y0914531D02*
X0756976Y0914407D01*
X0756447Y0914054*
X0756093Y0913524*
X0755969Y09129*
X0756093Y0912276*
X0756447Y0911747*
X0756976Y0911393*
X07576Y0911269*
X0758224Y0911393*
X0758753Y0911747*
X0759107Y0912276*
X0759231Y09129*
X0759107Y0913524*
X0758753Y0914054*
X0758224Y0914407*
X07576Y0914531*
G37*
G36*
X0994823Y0915594D02*
X0994151Y0915506D01*
X0993526Y0915246*
X0992989Y0914834*
X0992577Y0914297*
X0992317Y0913671*
X0992229Y0913*
X0992317Y0912329*
X0992577Y0911703*
X0992989Y0911166*
X0993526Y0910754*
X0994151Y0910495*
X0994823Y0910406*
X0995494Y0910495*
X099612Y0910754*
X0996657Y0911166*
X0997069Y0911703*
X0997328Y0912329*
X0997417Y0913*
X0997328Y0913671*
X0997069Y0914297*
X0996657Y0914834*
X099612Y0915246*
X0995494Y0915506*
X0994823Y0915594*
G37*
G36*
X09775D02*
X0976829Y0915506D01*
X0976203Y0915246*
X0975666Y0914834*
X0975254Y0914297*
X0974994Y0913671*
X0974906Y0913*
X0974994Y0912329*
X0975254Y0911703*
X0975666Y0911166*
X0976203Y0910754*
X0976829Y0910495*
X09775Y0910406*
X0978171Y0910495*
X0978797Y0910754*
X0979334Y0911166*
X0979746Y0911703*
X0980005Y0912329*
X0980094Y0913*
X0980005Y0913671*
X0979746Y0914297*
X0979334Y0914834*
X0978797Y0915246*
X0978171Y0915506*
X09775Y0915594*
G37*
G36*
X1074487Y0913618D02*
X1073863Y0913494D01*
X1073333Y091314*
X107298Y0912611*
X1072856Y0911987*
X107298Y0911363*
X1073333Y0910833*
X1073863Y091048*
X1074487Y0910356*
X1075111Y091048*
X107564Y0910833*
X1075994Y0911363*
X1076118Y0911987*
X1075994Y0912611*
X107564Y091314*
X1075111Y0913494*
X1074487Y0913618*
G37*
G36*
X117122Y0919881D02*
X1169727Y0919684D01*
X1168335Y0919108*
X116714Y0918191*
X1166223Y0916996*
X1165646Y0915604*
X116545Y091411*
X1165646Y0912617*
X1166223Y0911225*
X116714Y091003*
X1168335Y0909113*
X1169727Y0908536*
X117122Y090834*
X1172714Y0908536*
X1174106Y0909113*
X1175301Y091003*
X1176218Y0911225*
X1176795Y0912617*
X1176991Y091411*
X1176795Y0915604*
X1176218Y0916996*
X1175301Y0918191*
X1174106Y0919108*
X1172714Y0919684*
X117122Y0919881*
G37*
G36*
X1125716Y0910915D02*
X1125092Y0910791D01*
X1124563Y0910437*
X1124209Y0909908*
X1124085Y0909284*
X1124209Y0908659*
X1124563Y090813*
X1125092Y0907776*
X1125716Y0907652*
X1126341Y0907776*
X112687Y090813*
X1127224Y0908659*
X1127348Y0909284*
X1127224Y0909908*
X112687Y0910437*
X1126341Y0910791*
X1125716Y0910915*
G37*
G36*
X09495Y0910631D02*
X0948876Y0910507D01*
X0948347Y0910153*
X0947993Y0909624*
X0947869Y0909*
X0947993Y0908376*
X0948347Y0907847*
X0948876Y0907493*
X09495Y0907369*
X0950124Y0907493*
X0950653Y0907847*
X0951007Y0908376*
X0951131Y0909*
X0951007Y0909624*
X0950653Y0910153*
X0950124Y0910507*
X09495Y0910631*
G37*
G36*
X09285Y0913138D02*
X092743Y0912998D01*
X0926433Y0912585*
X0925576Y0911928*
X0924919Y0911071*
X0924506Y0910074*
X0924365Y0909004*
X0924506Y0907934*
X0924919Y0906937*
X0925576Y090608*
X0926433Y0905423*
X092743Y090501*
X09285Y0904869*
X092957Y090501*
X0930567Y0905423*
X0931424Y090608*
X0932081Y0906937*
X0932494Y0907934*
X0932635Y0909004*
X0932494Y0910074*
X0932081Y0911071*
X0931424Y0911928*
X0930567Y0912585*
X092957Y0912998*
X09285Y0913138*
G37*
G36*
X08985D02*
X089743Y0912998D01*
X0896433Y0912585*
X0895576Y0911928*
X0894919Y0911071*
X0894506Y0910074*
X0894365Y0909004*
X0894506Y0907934*
X0894919Y0906937*
X0895576Y090608*
X0896433Y0905423*
X089743Y090501*
X08985Y0904869*
X089957Y090501*
X0900567Y0905423*
X0901424Y090608*
X0902081Y0906937*
X0902494Y0907934*
X0902635Y0909004*
X0902494Y0910074*
X0902081Y0911071*
X0901424Y0911928*
X0900567Y0912585*
X089957Y0912998*
X08985Y0913138*
G37*
G36*
X13206Y0930141D02*
X1318513Y0929977D01*
X1316477Y0929488*
X1314543Y0928687*
X1312758Y0927593*
X1311166Y0926234*
X1309807Y0924642*
X1308713Y0922857*
X1307912Y0920923*
X1307423Y0918887*
X1307259Y09168*
X1307423Y0914713*
X1307912Y0912677*
X1308713Y0910743*
X1309807Y0908958*
X1311166Y0907366*
X1312758Y0906007*
X1314543Y0904913*
X1316477Y0904112*
X1318513Y0903623*
X13206Y0903459*
X1322687Y0903623*
X1324723Y0904112*
X1326657Y0904913*
X1328442Y0906007*
X1330034Y0907366*
X1331393Y0908958*
X1332487Y0910743*
X1333288Y0912677*
X1333777Y0914713*
X1333941Y09168*
X1333777Y0918887*
X1333288Y0920923*
X1332487Y0922857*
X1331393Y0924642*
X1330034Y0926234*
X1328442Y0927593*
X1326657Y0928687*
X1324723Y0929488*
X1322687Y0929977*
X13206Y0930141*
G37*
G36*
X1289035Y0916478D02*
X1287721Y0916349D01*
X1286457Y0915965*
X1285292Y0915343*
X1284271Y0914505*
X1283433Y0913484*
X128281Y0912319*
X1282427Y0911055*
X1282298Y090974*
X1282427Y0908426*
X128281Y0907162*
X1283433Y0905997*
X1284271Y0904976*
X1285292Y0904138*
X1286457Y0903515*
X1287721Y0903132*
X1289035Y0903002*
X129035Y0903132*
X1291614Y0903515*
X1292779Y0904138*
X12938Y0904976*
X1294638Y0905997*
X1295261Y0907162*
X1295644Y0908426*
X1295773Y090974*
X1295644Y0911055*
X1295261Y0912319*
X1294638Y0913484*
X12938Y0914505*
X1292779Y0915343*
X1291614Y0915965*
X129035Y0916349*
X1289035Y0916478*
G37*
G36*
X1255965D02*
X125465Y0916349D01*
X1253386Y0915965*
X1252221Y0915343*
X12512Y0914505*
X1250362Y0913484*
X1249739Y0912319*
X1249356Y0911055*
X1249227Y090974*
X1249356Y0908426*
X1249739Y0907162*
X1250362Y0905997*
X12512Y0904976*
X1252221Y0904138*
X1253386Y0903515*
X125465Y0903132*
X1255965Y0903002*
X1257279Y0903132*
X1258543Y0903515*
X1259708Y0904138*
X1260729Y0904976*
X1261567Y0905997*
X126219Y0907162*
X1262573Y0908426*
X1262702Y090974*
X1262573Y0911055*
X126219Y0912319*
X1261567Y0913484*
X1260729Y0914505*
X1259708Y0915343*
X1258543Y0915965*
X1257279Y0916349*
X1255965Y0916478*
G37*
G36*
X07429Y0909981D02*
X0741973Y0909859D01*
X074111Y0909501*
X0740368Y0908932*
X0739799Y090819*
X0739441Y0907327*
X0739319Y09064*
X0739441Y0905473*
X0739799Y090461*
X0740368Y0903868*
X074111Y0903299*
X0741973Y0902941*
X07429Y0902819*
X0743827Y0902941*
X074469Y0903299*
X0745432Y0903868*
X0746001Y090461*
X0746359Y0905473*
X0746481Y09064*
X0746359Y0907327*
X0746001Y090819*
X0745432Y0908932*
X074469Y0909501*
X0743827Y0909859*
X07429Y0909981*
G37*
G36*
X06294Y0928941D02*
X0627313Y0928777D01*
X0625277Y0928288*
X0623343Y0927487*
X0621558Y0926393*
X0619966Y0925034*
X0618607Y0923442*
X0617513Y0921657*
X0616712Y0919723*
X0616223Y0917687*
X0616059Y09156*
X0616223Y0913513*
X0616712Y0911477*
X0617513Y0909543*
X0618607Y0907758*
X0619966Y0906166*
X0621558Y0904807*
X0623343Y0903713*
X0625277Y0902912*
X0627313Y0902423*
X06294Y0902259*
X0631487Y0902423*
X0633523Y0902912*
X0635457Y0903713*
X0637242Y0904807*
X0638834Y0906166*
X0640193Y0907758*
X0641287Y0909543*
X0642088Y0911477*
X0642577Y0913513*
X0642741Y09156*
X0642577Y0917687*
X0642088Y0919723*
X0641287Y0921657*
X0640193Y0923442*
X0638834Y0925034*
X0637242Y0926393*
X0635457Y0927487*
X0633523Y0928288*
X0631487Y0928777*
X06294Y0928941*
G37*
G36*
X0803Y0909181D02*
X0802073Y0909059D01*
X080121Y0908701*
X0800468Y0908132*
X0799899Y090739*
X0799541Y0906527*
X0799419Y09056*
X0799541Y0904673*
X0799899Y090381*
X0800468Y0903068*
X080121Y0902499*
X0802073Y0902141*
X0803Y0902019*
X0803927Y0902141*
X080479Y0902499*
X0805532Y0903068*
X0806101Y090381*
X0806459Y0904673*
X0806581Y09056*
X0806459Y0906527*
X0806101Y090739*
X0805532Y0908132*
X080479Y0908701*
X0803927Y0909059*
X0803Y0909181*
G37*
G36*
X07894Y0903831D02*
X0788776Y0903707D01*
X0788246Y0903354*
X0787893Y0902824*
X0787769Y09022*
X0787893Y0901576*
X0788246Y0901046*
X0788776Y0900693*
X07894Y0900569*
X0790024Y0900693*
X0790554Y0901046*
X0790907Y0901576*
X0791031Y09022*
X0790907Y0902824*
X0790554Y0903354*
X0790024Y0903707*
X07894Y0903831*
G37*
G36*
X08235Y0903731D02*
X0822876Y0903607D01*
X0822346Y0903253*
X0821993Y0902724*
X0821869Y09021*
X0821993Y0901476*
X0822346Y0900947*
X0822876Y0900593*
X08235Y0900469*
X0824124Y0900593*
X0824654Y0900947*
X0825007Y0901476*
X0825131Y09021*
X0825007Y0902724*
X0824654Y0903253*
X0824124Y0903607*
X08235Y0903731*
G37*
G36*
X117122Y0901771D02*
X1169727Y0901574D01*
X1168335Y0900998*
X116714Y090008*
X1166223Y0898885*
X1165646Y0897493*
X116545Y0896*
X1165646Y0894506*
X1166223Y0893115*
X116714Y089192*
X1168335Y0891002*
X1169727Y0890426*
X117122Y0890229*
X1172714Y0890426*
X1174106Y0891002*
X1175301Y089192*
X1176218Y0893115*
X1176795Y0894506*
X1176991Y0896*
X1176795Y0897493*
X1176218Y0898885*
X1175301Y090008*
X1174106Y0900998*
X1172714Y0901574*
X117122Y0901771*
G37*
G36*
X08075Y0891631D02*
X0806876Y0891507D01*
X0806347Y0891154*
X0805993Y0890624*
X0805869Y089*
X0805993Y0889376*
X0806009Y0889351*
X0805649Y0888991*
X0805624Y0889007*
X0805Y0889131*
X0804376Y0889007*
X0803846Y0888653*
X0803493Y0888124*
X0803369Y08875*
X0803493Y0886876*
X0803846Y0886347*
X0804376Y0885993*
X0805Y0885869*
X0805624Y0885993*
X0806153Y0886347*
X0806507Y0886876*
X0806631Y08875*
X0806507Y0888124*
X0806491Y0888149*
X0806851Y0888509*
X0806876Y0888493*
X08075Y0888369*
X0808124Y0888493*
X0808654Y0888846*
X0809007Y0889376*
X0809131Y089*
X0809007Y0890624*
X0808654Y0891154*
X0808124Y0891507*
X08075Y0891631*
G37*
G36*
X0802Y0885631D02*
X0801376Y0885507D01*
X0800846Y0885153*
X0800493Y0884624*
X0800369Y0884*
X0800383Y0883927*
X0800325Y0883832*
X079995Y0883542*
X07995Y0883631*
X0798876Y0883507*
X0798347Y0883154*
X0797993Y0882624*
X0797869Y0882*
X0797993Y0881376*
X0798347Y0880847*
X0798876Y0880493*
X07995Y0880369*
X0800124Y0880493*
X0800653Y0880847*
X0801007Y0881376*
X0801131Y0882*
X0801117Y0882073*
X0801175Y0882168*
X080155Y0882458*
X0802Y0882369*
X0802624Y0882493*
X0803154Y0882847*
X0803507Y0883376*
X0803631Y0884*
X0803507Y0884624*
X0803154Y0885153*
X0802624Y0885507*
X0802Y0885631*
G37*
G36*
X0969D02*
X0968376Y0885507D01*
X0967846Y0885153*
X0967493Y0884624*
X0967369Y0884*
X0967493Y0883376*
X0967846Y0882847*
X0968376Y0882493*
X0969Y0882369*
X0969624Y0882493*
X0970154Y0882847*
X0970507Y0883376*
X0970631Y0884*
X0970507Y0884624*
X0970154Y0885153*
X0969624Y0885507*
X0969Y0885631*
G37*
G36*
X09005Y0885131D02*
X0899876Y0885007D01*
X0899347Y0884653*
X0898993Y0884124*
X0898869Y08835*
X0898993Y0882876*
X0899347Y0882347*
X0899876Y0881993*
X09005Y0881869*
X0901124Y0881993*
X0901653Y0882347*
X0902007Y0882876*
X0902131Y08835*
X0902007Y0884124*
X0901653Y0884653*
X0901124Y0885007*
X09005Y0885131*
G37*
G36*
X0982Y0882631D02*
X0981376Y0882507D01*
X0980847Y0882154*
X0980493Y0881624*
X0980369Y0881*
X0980493Y0880376*
X0980847Y0879846*
X0981376Y0879493*
X0982Y0879369*
X0982624Y0879493*
X0983154Y0879846*
X0983507Y0880376*
X0983631Y0881*
X0983507Y0881624*
X0983154Y0882154*
X0982624Y0882507*
X0982Y0882631*
G37*
G36*
X0953D02*
X0952376Y0882507D01*
X0951847Y0882154*
X0951493Y0881624*
X0951369Y0881*
X0951493Y0880376*
X0951847Y0879846*
X0952376Y0879493*
X0953Y0879369*
X0953624Y0879493*
X0954154Y0879846*
X0954507Y0880376*
X0954631Y0881*
X0954507Y0881624*
X0954154Y0882154*
X0953624Y0882507*
X0953Y0882631*
G37*
G36*
X0921D02*
X0920376Y0882507D01*
X0919847Y0882154*
X0919493Y0881624*
X0919369Y0881*
X0919493Y0880376*
X0919847Y0879846*
X0920376Y0879493*
X0921Y0879369*
X0921624Y0879493*
X0922153Y0879846*
X0922507Y0880376*
X0922631Y0881*
X0922507Y0881624*
X0922153Y0882154*
X0921624Y0882507*
X0921Y0882631*
G37*
G36*
X0871257Y0880632D02*
X0870632Y0880508D01*
X0870103Y0880154*
X086975Y0879625*
X0869625Y0879001*
X086975Y0878376*
X0870103Y0877847*
X0870632Y0877494*
X0871257Y0877369*
X0871881Y0877494*
X087241Y0877847*
X0872764Y0878376*
X0872888Y0879001*
X0872764Y0879625*
X087241Y0880154*
X0871881Y0880508*
X0871257Y0880632*
G37*
G36*
X1215921Y0888149D02*
X1206079D01*
X1204585Y0887952*
X1203193Y0887376*
X1201998Y0886458*
X1201081Y0885263*
X1200505Y0883871*
X1200308Y0882378*
X1200505Y0880884*
X1201081Y0879493*
X1201998Y0878298*
X1203193Y087738*
X1204585Y0876804*
X1206079Y0876607*
X1215921*
X1217415Y0876804*
X1218807Y087738*
X1220002Y0878298*
X1220919Y0879493*
X1221495Y0880884*
X1221692Y0882378*
X1221495Y0883871*
X1220919Y0885263*
X1220002Y0886458*
X1218807Y0887376*
X1217415Y0887952*
X1215921Y0888149*
G37*
G36*
X10245Y0879631D02*
X1023876Y0879507D01*
X1023347Y0879154*
X1022993Y0878624*
X1022869Y0878*
X1022993Y0877376*
X1023347Y0876847*
X1023876Y0876493*
X10245Y0876369*
X1025124Y0876493*
X1025653Y0876847*
X1026007Y0877376*
X1026131Y0878*
X1026007Y0878624*
X1025653Y0879154*
X1025124Y0879507*
X10245Y0879631*
G37*
G36*
X1289035Y0886771D02*
X1287542Y0886574D01*
X128615Y0885997*
X1284955Y0885081*
X1284038Y0883885*
X1283461Y0882493*
X1283265Y0881*
X1283461Y0879506*
X1284038Y0878115*
X1284955Y0876919*
X128615Y0876003*
X1287542Y0875426*
X1289035Y0875229*
X1290529Y0875426*
X1291921Y0876003*
X1293116Y0876919*
X1294033Y0878115*
X1294609Y0879506*
X1294806Y0881*
X1294609Y0882493*
X1294033Y0883885*
X1293116Y0885081*
X1291921Y0885997*
X1290529Y0886574*
X1289035Y0886771*
G37*
G36*
X1255965D02*
X1254471Y0886574D01*
X1253079Y0885997*
X1251884Y0885081*
X1250967Y0883885*
X1250391Y0882493*
X1250194Y0881*
X1250391Y0879506*
X1250967Y0878115*
X1251884Y0876919*
X1253079Y0876003*
X1254471Y0875426*
X1255965Y0875229*
X1257458Y0875426*
X125885Y0876003*
X1260045Y0876919*
X1260962Y0878115*
X1261539Y0879506*
X1261735Y0881*
X1261539Y0882493*
X1260962Y0883885*
X1260045Y0885081*
X125885Y0885997*
X1257458Y0886574*
X1255965Y0886771*
G37*
G36*
X0969Y0877131D02*
X0968376Y0877007D01*
X0967846Y0876653*
X0967493Y0876124*
X0967369Y08755*
X0967493Y0874876*
X0967846Y0874347*
X0968376Y0873993*
X0969Y0873869*
X0969624Y0873993*
X0970154Y0874347*
X0970507Y0874876*
X0970631Y08755*
X0970507Y0876124*
X0970154Y0876653*
X0969624Y0877007*
X0969Y0877131*
G37*
G36*
X0898354D02*
X089773Y0877007D01*
X0897201Y0876653*
X0896847Y0876124*
X0896723Y08755*
X0896847Y0874876*
X0897201Y0874347*
X089773Y0873993*
X0898354Y0873869*
X0898979Y0873993*
X0899508Y0874347*
X0899862Y0874876*
X0899986Y08755*
X0899862Y0876124*
X0899508Y0876653*
X0898979Y0877007*
X0898354Y0877131*
G37*
G36*
X12285Y0872131D02*
X1227876Y0872007D01*
X1227347Y0871653*
X1226993Y0871124*
X1226869Y08705*
X1226993Y0869876*
X1227347Y0869347*
X1227876Y0868993*
X12285Y0868869*
X1229124Y0868993*
X1229653Y0869347*
X1230007Y0869876*
X1230131Y08705*
X1230007Y0871124*
X1229653Y0871653*
X1229124Y0872007*
X12285Y0872131*
G37*
G36*
X0784D02*
X0783376Y0872007D01*
X0782846Y0871653*
X0782493Y0871124*
X0782369Y08705*
X0782493Y0869876*
X0782846Y0869347*
X0783376Y0868993*
X0784Y0868869*
X0784624Y0868993*
X0785153Y0869347*
X0785507Y0869876*
X0785631Y08705*
X0785507Y0871124*
X0785153Y0871653*
X0784624Y0872007*
X0784Y0872131*
G37*
G36*
X1004Y0868531D02*
X1003376Y0868407D01*
X1002847Y0868054*
X1002493Y0867524*
X1002369Y08669*
X1002493Y0866276*
X1002847Y0865746*
X1003376Y0865393*
X1004Y0865269*
X1004624Y0865393*
X1005153Y0865746*
X1005507Y0866276*
X1005631Y08669*
X1005507Y0867524*
X1005153Y0868054*
X1004624Y0868407*
X1004Y0868531*
G37*
G36*
X0867Y0868131D02*
X0866376Y0868007D01*
X0865847Y0867653*
X0865493Y0867124*
X0865369Y08665*
X0865493Y0865876*
X0865847Y0865347*
X0866376Y0864993*
X0867Y0864869*
X0867624Y0864993*
X0868153Y0865347*
X0868507Y0865876*
X0868631Y08665*
X0868507Y0867124*
X0868153Y0867653*
X0867624Y0868007*
X0867Y0868131*
G37*
G36*
X07745D02*
X0773876Y0868007D01*
X0773347Y0867653*
X0772993Y0867124*
X0772869Y08665*
X0772993Y0865876*
X0773347Y0865347*
X0773876Y0864993*
X07745Y0864869*
X0775124Y0864993*
X0775654Y0865347*
X0776007Y0865876*
X0776131Y08665*
X0776007Y0867124*
X0775654Y0867653*
X0775124Y0868007*
X07745Y0868131*
G37*
G36*
X09415Y0865631D02*
X0940876Y0865507D01*
X0940347Y0865154*
X0939993Y0864624*
X0939869Y0864*
X0939993Y0863376*
X0940347Y0862846*
X0940876Y0862493*
X09415Y0862369*
X0942124Y0862493*
X0942653Y0862846*
X0943007Y0863376*
X0943131Y0864*
X0943007Y0864624*
X0942653Y0865154*
X0942124Y0865507*
X09415Y0865631*
G37*
G36*
X09265Y0862631D02*
X0925876Y0862507D01*
X0925346Y0862154*
X0924993Y0861624*
X0924869Y0861*
X0924873Y0860976*
X0924402Y0860781*
X0924154Y0861154*
X0923624Y0861507*
X0923Y0861631*
X0922376Y0861507*
X0921846Y0861154*
X0921493Y0860624*
X0921369Y086*
X0921493Y0859376*
X0921846Y0858846*
X0922376Y0858493*
X0923Y0858369*
X0923624Y0858493*
X0924154Y0858846*
X0924507Y0859376*
X0924631Y086*
X0924627Y0860024*
X0925098Y0860219*
X0925346Y0859846*
X0925876Y0859493*
X09265Y0859369*
X0927124Y0859493*
X0927654Y0859846*
X0928007Y0860376*
X0928131Y0861*
X0928007Y0861624*
X0927654Y0862154*
X0927124Y0862507*
X09265Y0862631*
G37*
G36*
X0879Y0863631D02*
X0878376Y0863507D01*
X0877847Y0863153*
X0877493Y0862624*
X0877369Y0862*
X0877493Y0861376*
X0877847Y0860847*
X0878376Y0860493*
X0879Y0860369*
X0879624Y0860493*
X0880153Y0860847*
X0880507Y0861376*
X0880631Y0862*
X0880507Y0862624*
X0880153Y0863153*
X0879624Y0863507*
X0879Y0863631*
G37*
G36*
X0813Y0863131D02*
X0812376Y0863007D01*
X0811847Y0862654*
X0811493Y0862124*
X0811369Y08615*
X0811493Y0860876*
X0811847Y0860347*
X0812376Y0859993*
X0813Y0859869*
X0813624Y0859993*
X0814153Y0860347*
X0814507Y0860876*
X0814631Y08615*
X0814507Y0862124*
X0814153Y0862654*
X0813624Y0863007*
X0813Y0863131*
G37*
G36*
X1066Y0862631D02*
X1065376Y0862507D01*
X1064847Y0862154*
X1064493Y0861624*
X1064369Y0861*
X1064493Y0860376*
X1064847Y0859846*
X1065376Y0859493*
X1066Y0859369*
X1066624Y0859493*
X1067153Y0859846*
X1067507Y0860376*
X1067631Y0861*
X1067507Y0861624*
X1067153Y0862154*
X1066624Y0862507*
X1066Y0862631*
G37*
G36*
X07875Y0862131D02*
X0786876Y0862007D01*
X0786346Y0861654*
X0785993Y0861124*
X0785869Y08605*
X0785993Y0859876*
X0786346Y0859346*
X0786876Y0858993*
X07875Y0858869*
X0788124Y0858993*
X0788654Y0859346*
X0789007Y0859876*
X0789131Y08605*
X0789007Y0861124*
X0788654Y0861654*
X0788124Y0862007*
X07875Y0862131*
G37*
G36*
X0754Y0864131D02*
X0753376Y0864007D01*
X0752846Y0863653*
X0752493Y0863124*
X0752369Y08625*
X0752493Y0861876*
X0752846Y0861347*
X0753376Y0860993*
X0754Y0860869*
X0754624Y0860993*
X0754649Y0861009*
X0755009Y0860649*
X0754993Y0860624*
X0754869Y086*
X0754993Y0859376*
X0755346Y0858846*
X0755876Y0858493*
X07565Y0858369*
X0757124Y0858493*
X0757654Y0858846*
X0758007Y0859376*
X0758131Y086*
X0758007Y0860624*
X0757654Y0861154*
X0757124Y0861507*
X07565Y0861631*
X0755876Y0861507*
X0755851Y0861491*
X0755491Y0861851*
X0755507Y0861876*
X0755631Y08625*
X0755507Y0863124*
X0755154Y0863653*
X0754624Y0864007*
X0754Y0864131*
G37*
G36*
X084075Y0863026D02*
X0839854Y0862848D01*
X0839095Y086234*
X0838587Y0861581*
X0838409Y0860685*
X0838587Y0859789*
X0839095Y085903*
X0839854Y0858522*
X084075Y0858344*
X0841646Y0858522*
X0842405Y085903*
X0842913Y0859789*
X0843091Y0860685*
X0842913Y0861581*
X0842405Y086234*
X0841646Y0862848*
X084075Y0863026*
G37*
G36*
X08765Y0858631D02*
X0875876Y0858507D01*
X0875346Y0858154*
X0874993Y0857624*
X0874869Y0857*
X0874993Y0856376*
X0875346Y0855847*
X0875876Y0855493*
X08765Y0855369*
X0877124Y0855493*
X0877654Y0855847*
X0878007Y0856376*
X0878131Y0857*
X0878007Y0857624*
X0877654Y0858154*
X0877124Y0858507*
X08765Y0858631*
G37*
G36*
X07431Y0857731D02*
X0742476Y0857607D01*
X0741947Y0857253*
X0741593Y0856724*
X0741469Y08561*
X0741593Y0855476*
X0741947Y0854947*
X0742476Y0854593*
X07431Y0854469*
X0743724Y0854593*
X0744253Y0854947*
X0744607Y0855476*
X0744731Y08561*
X0744607Y0856724*
X0744253Y0857253*
X0743724Y0857607*
X07431Y0857731*
G37*
G36*
X11985Y0857231D02*
X1197876Y0857107D01*
X1197346Y0856754*
X1196993Y0856224*
X1196869Y08556*
X1196993Y0854976*
X1197346Y0854447*
X1197876Y0854093*
X11985Y0853969*
X1199124Y0854093*
X1199654Y0854447*
X1200007Y0854976*
X1200131Y08556*
X1200007Y0856224*
X1199654Y0856754*
X1199124Y0857107*
X11985Y0857231*
G37*
G36*
X12725Y0865117D02*
X1271006Y0864921D01*
X1269615Y0864344*
X1268419Y0863427*
X1267502Y0862232*
X1266926Y086084*
X1266729Y0859346*
X1266926Y0857853*
X1267502Y0856461*
X1268419Y0855266*
X1269615Y0854349*
X1271006Y0853773*
X12725Y0853576*
X1273993Y0853773*
X1275385Y0854349*
X1276581Y0855266*
X1277497Y0856461*
X1278074Y0857853*
X1278271Y0859346*
X1278074Y086084*
X1277497Y0862232*
X1276581Y0863427*
X1275385Y0864344*
X1273993Y0864921*
X12725Y0865117*
G37*
G36*
X08425Y0856631D02*
X0841876Y0856507D01*
X0841346Y0856153*
X0840993Y0855624*
X0840869Y0855*
X0840993Y0854376*
X0841346Y0853846*
X0841876Y0853493*
X08425Y0853369*
X0843124Y0853493*
X0843653Y0853846*
X0844007Y0854376*
X0844131Y0855*
X0844007Y0855624*
X0843653Y0856153*
X0843124Y0856507*
X08425Y0856631*
G37*
G36*
X08245Y0855631D02*
X0823876Y0855507D01*
X0823347Y0855153*
X0822993Y0854624*
X0822869Y0854*
X0822993Y0853376*
X0823265Y0852969*
X082298Y0852536*
X08225Y0852631*
X0821876Y0852507*
X0821346Y0852153*
X0820993Y0851624*
X0820869Y0851*
X0820993Y0850376*
X0821346Y0849846*
X0821876Y0849493*
X08225Y0849369*
X0823124Y0849493*
X0823654Y0849846*
X0824007Y0850376*
X0824131Y0851*
X0824007Y0851624*
X0823735Y0852031*
X082402Y0852464*
X08245Y0852369*
X0825124Y0852493*
X0825653Y0852847*
X0826007Y0853376*
X0826131Y0854*
X0826007Y0854624*
X0825653Y0855153*
X0825124Y0855507*
X08245Y0855631*
G37*
G36*
X11265Y0853131D02*
X1125876Y0853007D01*
X1125346Y0852654*
X1124993Y0852124*
X1124869Y08515*
X1124993Y0850876*
X1125346Y0850346*
X1125876Y0849993*
X11265Y0849869*
X1127124Y0849993*
X1127654Y0850346*
X1128007Y0850876*
X1128131Y08515*
X1128007Y0852124*
X1127654Y0852654*
X1127124Y0853007*
X11265Y0853131*
G37*
G36*
X09613Y0850631D02*
X0960676Y0850507D01*
X0960147Y0850154*
X0959793Y0849624*
X0959669Y0849*
X0959793Y0848376*
X0960147Y0847847*
X0960676Y0847493*
X09613Y0847369*
X0961924Y0847493*
X0962453Y0847847*
X0962807Y0848376*
X0962931Y0849*
X0962807Y0849624*
X0962453Y0850154*
X0961924Y0850507*
X09613Y0850631*
G37*
G36*
X0857D02*
X0856376Y0850507D01*
X0855847Y0850154*
X0855493Y0849624*
X0855369Y0849*
X0855493Y0848376*
X0855847Y0847847*
X0856376Y0847493*
X0857Y0847369*
X0857624Y0847493*
X0858154Y0847847*
X0858507Y0848376*
X0858631Y0849*
X0858507Y0849624*
X0858154Y0850154*
X0857624Y0850507*
X0857Y0850631*
G37*
G36*
X0952Y0850131D02*
X0951376Y0850007D01*
X0950846Y0849654*
X0950493Y0849124*
X0950369Y08485*
X0950493Y0847876*
X0950846Y0847346*
X0951376Y0846993*
X0952Y0846869*
X0952624Y0846993*
X0953154Y0847346*
X0953507Y0847876*
X0953631Y08485*
X0953507Y0849124*
X0953154Y0849654*
X0952624Y0850007*
X0952Y0850131*
G37*
G36*
X0838D02*
X0837376Y0850007D01*
X0836847Y0849654*
X0836493Y0849124*
X0836369Y08485*
X0836493Y0847876*
X0836847Y0847346*
X0837376Y0846993*
X0838Y0846869*
X0838624Y0846993*
X0839153Y0847346*
X0839507Y0847876*
X0839631Y08485*
X0839507Y0849124*
X0839153Y0849654*
X0838624Y0850007*
X0838Y0850131*
G37*
G36*
X125Y0847631D02*
X1249376Y0847507D01*
X1248847Y0847153*
X1248493Y0846624*
X1248369Y0846*
X1248493Y0845376*
X1248847Y0844847*
X1249376Y0844493*
X125Y0844369*
X1250624Y0844493*
X1251153Y0844847*
X1251507Y0845376*
X1251631Y0846*
X1251507Y0846624*
X1251153Y0847153*
X1250624Y0847507*
X125Y0847631*
G37*
G36*
X09427Y0847731D02*
X0942076Y0847607D01*
X0941547Y0847254*
X0941193Y0846724*
X0941069Y08461*
X0941193Y0845476*
X0941547Y0844946*
X0942076Y0844593*
X09427Y0844469*
X0943324Y0844593*
X0943853Y0844946*
X0944039Y0845224*
X0944077Y0845237*
X0944617Y0845189*
X0944847Y0844847*
X0945376Y0844493*
X0946Y0844369*
X0946624Y0844493*
X0947153Y0844847*
X0947507Y0845376*
X0947631Y0846*
X0947507Y0846624*
X0947153Y0847153*
X0946624Y0847507*
X0946Y0847631*
X0945376Y0847507*
X0944847Y0847153*
X0944661Y0846876*
X0944623Y0846863*
X0944083Y084691*
X0943853Y0847254*
X0943324Y0847607*
X09427Y0847731*
G37*
G36*
X09349Y0846831D02*
X0934276Y0846707D01*
X0933747Y0846354*
X0933393Y0845824*
X0933269Y08452*
X0933393Y0844576*
X0933747Y0844046*
X0934276Y0843693*
X09349Y0843569*
X0935524Y0843693*
X0936053Y0844046*
X0936407Y0844576*
X0936435Y0844716*
X0936945*
X0936993Y0844476*
X0937346Y0843946*
X0937876Y0843593*
X09385Y0843469*
X0939124Y0843593*
X0939653Y0843946*
X0940007Y0844476*
X0940131Y08451*
X0940007Y0845724*
X0939653Y0846253*
X0939124Y0846607*
X09385Y0846731*
X0937876Y0846607*
X0937346Y0846253*
X0936993Y0845724*
X0936965Y0845584*
X0936455*
X0936407Y0845824*
X0936053Y0846354*
X0935524Y0846707*
X09349Y0846831*
G37*
G36*
X084075Y0847278D02*
X0839854Y08471D01*
X0839095Y0846592*
X0838587Y0845833*
X0838409Y0844937*
X0838587Y0844041*
X0839095Y0843282*
X0839854Y0842774*
X084075Y0842596*
X0841646Y0842774*
X0842405Y0843282*
X0842913Y0844041*
X0843091Y0844937*
X0842913Y0845833*
X0842405Y0846592*
X0841646Y08471*
X084075Y0847278*
G37*
G36*
X1247Y0844631D02*
X1246376Y0844507D01*
X1245846Y0844153*
X1245493Y0843624*
X1245369Y0843*
X1245493Y0842376*
X1245846Y0841846*
X1246376Y0841493*
X1247Y0841369*
X1247624Y0841493*
X1248153Y0841846*
X1248507Y0842376*
X1248631Y0843*
X1248507Y0843624*
X1248153Y0844153*
X1247624Y0844507*
X1247Y0844631*
G37*
G36*
X08625Y0842631D02*
X0861876Y0842507D01*
X0861347Y0842153*
X0860993Y0841624*
X0860869Y0841*
X0860993Y0840376*
X0861347Y0839847*
X0861876Y0839493*
X08625Y0839369*
X0863124Y0839493*
X0863653Y0839847*
X0864007Y0840376*
X0864131Y0841*
X0864007Y0841624*
X0863653Y0842153*
X0863124Y0842507*
X08625Y0842631*
G37*
G36*
X1243773Y0841631D02*
X1243149Y0841507D01*
X124262Y0841154*
X1242266Y0840624*
X1242142Y084*
X1242266Y0839376*
X124262Y0838846*
X1243149Y0838493*
X1243773Y0838369*
X1244398Y0838493*
X1244927Y0838846*
X1245281Y0839376*
X1245405Y084*
X1245281Y0840624*
X1244927Y0841154*
X1244398Y0841507*
X1243773Y0841631*
G37*
G36*
X124Y0839131D02*
X1239376Y0839007D01*
X1238846Y0838653*
X1238493Y0838124*
X1238369Y08375*
X1238493Y0836876*
X1238846Y0836347*
X1239376Y0835993*
X124Y0835869*
X1240624Y0835993*
X1241154Y0836347*
X1241507Y0836876*
X1241631Y08375*
X1241507Y0838124*
X1241154Y0838653*
X1240624Y0839007*
X124Y0839131*
G37*
G36*
X09293Y0836431D02*
X0928676Y0836307D01*
X0928146Y0835954*
X0927793Y0835424*
X0927669Y08348*
X0927793Y0834176*
X0928146Y0833646*
X0928676Y0833293*
X09293Y0833169*
X0929924Y0833293*
X0930453Y0833646*
X0930807Y0834176*
X0930931Y08348*
X0930807Y0835424*
X0930453Y0835954*
X0929924Y0836307*
X09293Y0836431*
G37*
G36*
X1234491Y0835139D02*
X1233866Y0835015D01*
X1233337Y0834661*
X1232983Y0834132*
X1232859Y0833508*
X1232983Y0832883*
X1233337Y0832354*
X1233866Y0832*
X1234491Y0831876*
X1235115Y0832*
X1235644Y0832354*
X1235998Y0832883*
X1236122Y0833508*
X1235998Y0834132*
X1235644Y0834661*
X1235115Y0835015*
X1234491Y0835139*
G37*
G36*
X08717Y0834531D02*
X0871076Y0834407D01*
X0870547Y0834054*
X0870193Y0833524*
X0870069Y08329*
X0870193Y0832276*
X0870547Y0831746*
X0871076Y0831393*
X08717Y0831269*
X0872324Y0831393*
X0872853Y0831746*
X0873207Y0832276*
X0873331Y08329*
X0873207Y0833524*
X0872853Y0834054*
X0872324Y0834407*
X08717Y0834531*
G37*
G36*
X0953302Y0833929D02*
X0952678Y0833805D01*
X0952149Y0833451*
X0951795Y0832922*
X0951671Y0832298*
X0951795Y0831674*
X0952149Y0831144*
X0952678Y0830791*
X0953302Y0830666*
X0953926Y0830791*
X0954456Y0831144*
X0954809Y0831674*
X0954934Y0832298*
X0954809Y0832922*
X0954456Y0833451*
X0953926Y0833805*
X0953302Y0833929*
G37*
G36*
X09482Y0831731D02*
X0947576Y0831607D01*
X0947046Y0831254*
X0946693Y0830724*
X0946569Y08301*
X0946693Y0829476*
X0947046Y0828946*
X0947576Y0828593*
X09482Y0828469*
X0948824Y0828593*
X0949354Y0828946*
X0949707Y0829476*
X0949831Y08301*
X0949707Y0830724*
X0949354Y0831254*
X0948824Y0831607*
X09482Y0831731*
G37*
G36*
X09644Y0831331D02*
X0963776Y0831207D01*
X0963247Y0830853*
X0962893Y0830324*
X0962769Y08297*
X0962893Y0829076*
X0963247Y0828547*
X0963776Y0828193*
X09644Y0828069*
X0965024Y0828193*
X0965553Y0828547*
X0965907Y0829076*
X0966031Y08297*
X0965907Y0830324*
X0965553Y0830853*
X0965024Y0831207*
X09644Y0831331*
G37*
G36*
X09243D02*
X0923676Y0831207D01*
X0923147Y0830853*
X0922793Y0830324*
X0922669Y08297*
X0922793Y0829076*
X0923147Y0828547*
X0923676Y0828193*
X09243Y0828069*
X0924924Y0828193*
X0925453Y0828547*
X0925807Y0829076*
X0925931Y08297*
X0925807Y0830324*
X0925453Y0830853*
X0924924Y0831207*
X09243Y0831331*
G37*
G36*
X12435Y0831131D02*
X1242876Y0831007D01*
X1242346Y0830653*
X1241993Y0830124*
X1241869Y08295*
X1241993Y0828876*
X1242346Y0828347*
X1242876Y0827993*
X12435Y0827869*
X1244124Y0827993*
X1244654Y0828347*
X1245007Y0828876*
X1245131Y08295*
X1245007Y0830124*
X1244654Y0830653*
X1244124Y0831007*
X12435Y0831131*
G37*
G36*
X08581Y0830831D02*
X0857476Y0830707D01*
X0856946Y0830354*
X0856593Y0829824*
X0856469Y08292*
X0856593Y0828576*
X0856946Y0828047*
X0857476Y0827693*
X08581Y0827569*
X0858724Y0827693*
X0859254Y0828047*
X0859607Y0828576*
X0859731Y08292*
X0859607Y0829824*
X0859254Y0830354*
X0858724Y0830707*
X08581Y0830831*
G37*
G36*
X09365Y0829331D02*
X0935876Y0829207D01*
X0935347Y0828854*
X0934993Y0828324*
X0934869Y08277*
X0934993Y0827076*
X0935347Y0826546*
X0935876Y0826193*
X09365Y0826069*
X0937124Y0826193*
X0937654Y0826546*
X0938007Y0827076*
X0938131Y08277*
X0938007Y0828324*
X0937654Y0828854*
X0937124Y0829207*
X09365Y0829331*
G37*
G36*
X12325Y0828631D02*
X1231876Y0828507D01*
X1231347Y0828154*
X1230993Y0827624*
X1230869Y0827*
X1230993Y0826376*
X1231347Y0825846*
X1231876Y0825493*
X12325Y0825369*
X1233124Y0825493*
X1233654Y0825846*
X1234007Y0826376*
X1234131Y0827*
X1234007Y0827624*
X1233654Y0828154*
X1233124Y0828507*
X12325Y0828631*
G37*
G36*
X09735Y0828131D02*
X0972876Y0828007D01*
X0972346Y0827654*
X0971993Y0827124*
X0971869Y08265*
X0971993Y0825876*
X0972346Y0825346*
X0972876Y0824993*
X09735Y0824869*
X0974124Y0824993*
X0974654Y0825346*
X0975007Y0825876*
X0975131Y08265*
X0975007Y0827124*
X0974654Y0827654*
X0974124Y0828007*
X09735Y0828131*
G37*
G36*
X0825D02*
X0824376Y0828007D01*
X0823847Y0827654*
X0823493Y0827124*
X0823369Y08265*
X0823493Y0825876*
X0823847Y0825346*
X0824376Y0824993*
X0825Y0824869*
X0825624Y0824993*
X0826153Y0825346*
X0826507Y0825876*
X0826631Y08265*
X0826507Y0827124*
X0826153Y0827654*
X0825624Y0828007*
X0825Y0828131*
G37*
G36*
X09221Y0825531D02*
X0921476Y0825407D01*
X0920947Y0825054*
X0920593Y0824524*
X0920469Y08239*
X0920593Y0823276*
X0920947Y0822746*
X0921476Y0822393*
X09221Y0822269*
X0922724Y0822393*
X0923254Y0822746*
X0923607Y0823276*
X0923731Y08239*
X0923607Y0824524*
X0923254Y0825054*
X0922724Y0825407*
X09221Y0825531*
G37*
G36*
X084125Y0826704D02*
X0840354Y0826526D01*
X0839595Y0826018*
X0839087Y0825259*
X0838909Y0824363*
X0839087Y0823467*
X0839595Y0822708*
X0840354Y08222*
X084125Y0822022*
X0842146Y08222*
X0842905Y0822708*
X0843413Y0823467*
X0843591Y0824363*
X0843413Y0825259*
X0842905Y0826018*
X0842146Y0826526*
X084125Y0826704*
G37*
G36*
X1227257Y0824631D02*
X1226633Y0824507D01*
X1226104Y0824154*
X122575Y0823624*
X1225626Y0823*
X122575Y0822376*
X1226104Y0821846*
X1226633Y0821493*
X1227257Y0821369*
X1227882Y0821493*
X1228411Y0821846*
X1228765Y0822376*
X1228889Y0823*
X1228765Y0823624*
X1228411Y0824154*
X1227882Y0824507*
X1227257Y0824631*
G37*
G36*
X09797Y0825531D02*
X0979076Y0825407D01*
X0978547Y0825054*
X0978193Y0824524*
X0978069Y08239*
X0978193Y0823276*
X0978547Y0822746*
X0978772Y0822596*
X0978666Y0822065*
X0978376Y0822007*
X0977847Y0821653*
X0977493Y0821124*
X0977369Y08205*
X0977493Y0819876*
X0977847Y0819347*
X0978376Y0818993*
X0979Y0818869*
X0979624Y0818993*
X0980153Y0819347*
X0980507Y0819876*
X0980631Y08205*
X0980507Y0821124*
X0980153Y0821653*
X0979928Y0821804*
X0980034Y0822335*
X0980324Y0822393*
X0980853Y0822746*
X0981207Y0823276*
X0981331Y08239*
X0981207Y0824524*
X0980853Y0825054*
X0980324Y0825407*
X09797Y0825531*
G37*
G36*
X08582Y0822031D02*
X0857576Y0821907D01*
X0857047Y0821554*
X0856693Y0821024*
X0856569Y08204*
X0856693Y0819776*
X0857047Y0819246*
X0857576Y0818893*
X08582Y0818769*
X0858824Y0818893*
X0859354Y0819246*
X0859707Y0819776*
X0859831Y08204*
X0859707Y0821024*
X0859354Y0821554*
X0858824Y0821907*
X08582Y0822031*
G37*
G36*
X08196D02*
X0818976Y0821907D01*
X0818447Y0821554*
X0818093Y0821024*
X0817969Y08204*
X0818093Y0819776*
X0818447Y0819246*
X0818976Y0818893*
X08196Y0818769*
X0820224Y0818893*
X0820753Y0819246*
X0821107Y0819776*
X0821231Y08204*
X0821107Y0821024*
X0820753Y0821554*
X0820224Y0821907*
X08196Y0822031*
G37*
G36*
X1229957Y0821931D02*
X1229333Y0821807D01*
X1228804Y0821453*
X122845Y0820924*
X1228326Y08203*
X122845Y0819676*
X1228804Y0819147*
X1229333Y0818793*
X1229957Y0818669*
X1230582Y0818793*
X1231111Y0819147*
X1231464Y0819676*
X1231589Y08203*
X1231464Y0820924*
X1231111Y0821453*
X1230582Y0821807*
X1229957Y0821931*
G37*
G36*
X0841Y0821431D02*
X0840376Y0821307D01*
X0839847Y0820953*
X0839493Y0820424*
X0839369Y08198*
X0839493Y0819176*
X0839847Y0818647*
X0840376Y0818293*
X0841Y0818169*
X0841624Y0818293*
X0842153Y0818647*
X0842507Y0819176*
X0842631Y08198*
X0842507Y0820424*
X0842153Y0820953*
X0841624Y0821307*
X0841Y0821431*
G37*
G36*
X1243Y0821131D02*
X1242376Y0821007D01*
X1241846Y0820654*
X1241493Y0820124*
X1241369Y08195*
X1241493Y0818876*
X1241846Y0818347*
X1242376Y0817993*
X1243Y0817869*
X1243624Y0817993*
X1244153Y0818347*
X1244507Y0818876*
X1244631Y08195*
X1244507Y0820124*
X1244153Y0820654*
X1243624Y0821007*
X1243Y0821131*
G37*
G36*
X08716Y0818031D02*
X0870976Y0817907D01*
X0870446Y0817554*
X0870093Y0817024*
X0869969Y08164*
X0870093Y0815776*
X0870446Y0815246*
X0870976Y0814893*
X08716Y0814769*
X0872224Y0814893*
X0872754Y0815246*
X0873107Y0815776*
X0873231Y08164*
X0873107Y0817024*
X0872754Y0817554*
X0872224Y0817907*
X08716Y0818031*
G37*
G36*
X09048Y0817531D02*
X0904176Y0817407D01*
X0903646Y0817054*
X0903293Y0816524*
X0903169Y08159*
X0903293Y0815276*
X0903646Y0814746*
X0904176Y0814393*
X09048Y0814269*
X0905424Y0814393*
X0905954Y0814746*
X0906307Y0815276*
X0906431Y08159*
X0906307Y0816524*
X0905954Y0817054*
X0905424Y0817407*
X09048Y0817531*
G37*
G36*
X1233Y0817131D02*
X1232376Y0817007D01*
X1231847Y0816654*
X1231493Y0816124*
X1231369Y08155*
X1231493Y0814876*
X1231847Y0814347*
X1232376Y0813993*
X1233Y0813869*
X1233624Y0813993*
X1234153Y0814347*
X1234507Y0814876*
X1234631Y08155*
X1234507Y0816124*
X1234153Y0816654*
X1233624Y0817007*
X1233Y0817131*
G37*
G36*
X0982Y0819631D02*
X0981376Y0819507D01*
X0980847Y0819153*
X0980493Y0818624*
X0980369Y0818*
X0980493Y0817376*
X0980847Y0816846*
X0981376Y0816493*
X0982Y0816369*
X0982624Y0816493*
X0982649Y0816509*
X0983009Y0816149*
X0982993Y0816124*
X0982869Y08155*
X0982993Y0814876*
X0983346Y0814347*
X0983876Y0813993*
X09845Y0813869*
X0985124Y0813993*
X0985653Y0814347*
X0986007Y0814876*
X0986131Y08155*
X0986007Y0816124*
X0985653Y0816654*
X0985124Y0817007*
X09845Y0817131*
X0983876Y0817007*
X0983851Y0816991*
X0983491Y0817351*
X0983507Y0817376*
X0983631Y0818*
X0983507Y0818624*
X0983154Y0819153*
X0982624Y0819507*
X0982Y0819631*
G37*
G36*
X0745Y0816731D02*
X0744376Y0816607D01*
X0743847Y0816253*
X0743493Y0815724*
X0743369Y08151*
X0743493Y0814476*
X0743847Y0813947*
X0744376Y0813593*
X0745Y0813469*
X0745624Y0813593*
X0746153Y0813947*
X0746507Y0814476*
X0746631Y08151*
X0746507Y0815724*
X0746153Y0816253*
X0745624Y0816607*
X0745Y0816731*
G37*
G36*
X09592Y0815831D02*
X0958576Y0815707D01*
X0958047Y0815353*
X0957693Y0814824*
X0957569Y08142*
X0957693Y0813576*
X0958047Y0813046*
X0958576Y0812693*
X09592Y0812569*
X0959824Y0812693*
X0960353Y0813046*
X0960707Y0813576*
X0960831Y08142*
X0960707Y0814824*
X0960353Y0815353*
X0959824Y0815707*
X09592Y0815831*
G37*
G36*
X12295Y0814131D02*
X1228876Y0814007D01*
X1228347Y0813653*
X1227993Y0813124*
X1227869Y08125*
X1227993Y0811876*
X1228347Y0811347*
X1228876Y0810993*
X12295Y0810869*
X1230124Y0810993*
X1230653Y0811347*
X1231007Y0811876*
X1231131Y08125*
X1231007Y0813124*
X1230653Y0813653*
X1230124Y0814007*
X12295Y0814131*
G37*
G36*
X0993D02*
X0992376Y0814007D01*
X0991846Y0813653*
X0991493Y0813124*
X0991369Y08125*
X0991493Y0811876*
X0991846Y0811347*
X0992376Y0810993*
X0993Y0810869*
X0993624Y0810993*
X0994153Y0811347*
X0994507Y0811876*
X0994631Y08125*
X0994507Y0813124*
X0994153Y0813653*
X0993624Y0814007*
X0993Y0814131*
G37*
G36*
X09482Y0812331D02*
X0947576Y0812207D01*
X0947046Y0811854*
X0946693Y0811324*
X0946569Y08107*
X0946693Y0810076*
X0947046Y0809546*
X0947576Y0809193*
X09482Y0809069*
X0948824Y0809193*
X0949354Y0809546*
X0949707Y0810076*
X0949831Y08107*
X0949707Y0811324*
X0949354Y0811854*
X0948824Y0812207*
X09482Y0812331*
G37*
G36*
X08495Y0810231D02*
X0848876Y0810107D01*
X0848347Y0809754*
X0847993Y0809224*
X0847869Y08086*
X0847993Y0807976*
X0848347Y0807446*
X0848876Y0807093*
X08495Y0806969*
X0850124Y0807093*
X0850653Y0807446*
X0851007Y0807976*
X0851131Y08086*
X0851007Y0809224*
X0850653Y0809754*
X0850124Y0810107*
X08495Y0810231*
G37*
G36*
X08414Y0814331D02*
X0840776Y0814207D01*
X0840246Y0813853*
X0839893Y0813324*
X0839769Y08127*
X0839893Y0812076*
X0840246Y0811547*
X084057Y0811331*
X0840464Y08108*
X0840354Y0810778*
X0839595Y081027*
X0839087Y0809511*
X0838909Y0808615*
X0839087Y0807719*
X0839595Y080696*
X0840354Y0806452*
X084125Y0806274*
X0842146Y0806452*
X0842905Y080696*
X0843413Y0807719*
X0843591Y0808615*
X0843413Y0809511*
X0842905Y081027*
X084219Y0810748*
X0842179Y0810777*
X0842152Y0810984*
X0842161Y0811285*
X0842554Y0811547*
X0842907Y0812076*
X0843031Y08127*
X0842907Y0813324*
X0842554Y0813853*
X0842024Y0814207*
X08414Y0814331*
G37*
G36*
X09359Y0807031D02*
X0935276Y0806907D01*
X0934746Y0806553*
X0934393Y0806024*
X0934269Y08054*
X0934393Y0804776*
X0934746Y0804247*
X0935276Y0803893*
X09359Y0803769*
X0936524Y0803893*
X0937053Y0804247*
X0937407Y0804776*
X0937531Y08054*
X0937407Y0806024*
X0937053Y0806553*
X0936524Y0806907*
X09359Y0807031*
G37*
G36*
X08975Y0806631D02*
X0896876Y0806507D01*
X0896346Y0806153*
X0895993Y0805624*
X0895869Y0805*
X0895993Y0804376*
X0896346Y0803846*
X0896876Y0803493*
X08975Y0803369*
X0898124Y0803493*
X0898654Y0803846*
X0899007Y0804376*
X0899131Y0805*
X0899007Y0805624*
X0898654Y0806153*
X0898124Y0806507*
X08975Y0806631*
G37*
G36*
X09335Y0801631D02*
X0932876Y0801507D01*
X0932347Y0801153*
X0931993Y0800624*
X0931869Y08*
X0931993Y0799376*
X0932347Y0798846*
X0932876Y0798493*
X09335Y0798369*
X0934124Y0798493*
X0934653Y0798846*
X0935007Y0799376*
X0935131Y08*
X0935007Y0800624*
X0934653Y0801153*
X0934124Y0801507*
X09335Y0801631*
G37*
G36*
X0907Y0800131D02*
X0906376Y0800007D01*
X0905847Y0799653*
X0905493Y0799124*
X0905369Y07985*
X0905493Y0797876*
X0905847Y0797346*
X0906376Y0796993*
X0907Y0796869*
X0907624Y0796993*
X0908154Y0797346*
X0908507Y0797876*
X0908631Y07985*
X0908507Y0799124*
X0908154Y0799653*
X0907624Y0800007*
X0907Y0800131*
G37*
G36*
X09188Y0799031D02*
X0918176Y0798907D01*
X0917647Y0798554*
X0917293Y0798024*
X0917169Y07974*
X0917293Y0796776*
X0917647Y0796246*
X0918176Y0795893*
X09188Y0795769*
X0919424Y0795893*
X0919954Y0796246*
X0920307Y0796776*
X0920431Y07974*
X0920307Y0798024*
X0919954Y0798554*
X0919424Y0798907*
X09188Y0799031*
G37*
G36*
X0957Y0796331D02*
X0956376Y0796207D01*
X0955847Y0795854*
X0955493Y0795324*
X0955369Y07947*
X0955493Y0794076*
X0955847Y0793546*
X0956376Y0793193*
X0957Y0793069*
X0957624Y0793193*
X0958154Y0793546*
X0958507Y0794076*
X0958631Y07947*
X0958507Y0795324*
X0958154Y0795854*
X0957624Y0796207*
X0957Y0796331*
G37*
G36*
X09592Y0791231D02*
X0958576Y0791107D01*
X0958047Y0790754*
X0957693Y0790224*
X0957569Y07896*
X0957693Y0788976*
X0958047Y0788447*
X0958576Y0788093*
X09592Y0787969*
X0959824Y0788093*
X0960353Y0788447*
X0960707Y0788976*
X0960831Y07896*
X0960707Y0790224*
X0960353Y0790754*
X0959824Y0791107*
X09592Y0791231*
G37*
G36*
X1049382Y0781013D02*
X1048758Y0780889D01*
X1048228Y0780535*
X1047875Y0780006*
X104775Y0779382*
X1047875Y0778758*
X1048228Y0778228*
X1048758Y0777875*
X1049382Y077775*
X1050006Y0777875*
X1050535Y0778228*
X1050889Y0778758*
X1051013Y0779382*
X1050889Y0780006*
X1050535Y0780535*
X1050006Y0780889*
X1049382Y0781013*
G37*
G36*
X08137Y0777331D02*
X0813076Y0777207D01*
X0812547Y0776854*
X0812193Y0776324*
X0812069Y07757*
X0812193Y0775076*
X0812547Y0774546*
X0813076Y0774193*
X08137Y0774069*
X0814324Y0774193*
X0814853Y0774546*
X0815207Y0775076*
X0815331Y07757*
X0815207Y0776324*
X0814853Y0776854*
X0814324Y0777207*
X08137Y0777331*
G37*
G36*
X08485Y0771631D02*
X0847876Y0771507D01*
X0847346Y0771153*
X0846993Y0770624*
X0846869Y077*
X0846993Y0769376*
X0847346Y0768847*
X0847848Y0768511*
X0847876Y0768298*
Y0768202*
X0847848Y0767989*
X0847346Y0767654*
X0846993Y0767124*
X0846869Y07665*
X0846993Y0765876*
X0847346Y0765346*
X0847876Y0764993*
X08485Y0764869*
X0849124Y0764993*
X0849654Y0765346*
X0850007Y0765876*
X0850131Y07665*
X0850007Y0767124*
X0849654Y0767654*
X0849152Y0767989*
X0849124Y0768202*
Y0768298*
X0849152Y0768511*
X0849654Y0768847*
X0850007Y0769376*
X0850131Y077*
X0850007Y0770624*
X0849654Y0771153*
X0849124Y0771507*
X08485Y0771631*
G37*
G36*
X08949Y0764131D02*
X0894276Y0764007D01*
X0893746Y0763654*
X0893393Y0763124*
X0893269Y07625*
X0893393Y0761876*
X0893746Y0761346*
X0894276Y0760993*
X08949Y0760869*
X0895524Y0760993*
X0896054Y0761346*
X0896407Y0761876*
X0896531Y07625*
X0896407Y0763124*
X0896054Y0763654*
X0895524Y0764007*
X08949Y0764131*
G37*
G36*
X0841935D02*
X0841311Y0764007D01*
X0840781Y0763654*
X0840428Y0763124*
X0840304Y07625*
X0840428Y0761876*
X0840781Y0761346*
X0841311Y0760993*
X0841935Y0760869*
X0842559Y0760993*
X0843089Y0761346*
X0843442Y0761876*
X0843566Y07625*
X0843442Y0763124*
X0843089Y0763654*
X0842559Y0764007*
X0841935Y0764131*
G37*
G36*
X082425Y0763381D02*
X0823626Y0763257D01*
X0823096Y0762903*
X0822743Y0762374*
X0822619Y076175*
X0822743Y0761126*
X0822991Y0760755*
X0822661Y0760348*
X082219Y0760441*
X0821566Y0760317*
X0821037Y0759964*
X0820683Y0759434*
X0820559Y075881*
X0820683Y0758186*
X0821037Y0757656*
X0821566Y0757303*
X082219Y0757179*
X0822814Y0757303*
X0823343Y0757656*
X0823697Y0758186*
X0823821Y075881*
X0823697Y0759434*
X082345Y0759805*
X0823779Y0760212*
X082425Y0760119*
X0824874Y0760243*
X0825403Y0760597*
X0825757Y0761126*
X0825881Y076175*
X0825757Y0762374*
X0825403Y0762903*
X0824874Y0763257*
X082425Y0763381*
G37*
G36*
X08812Y0762131D02*
X0880576Y0762007D01*
X0880046Y0761654*
X0879693Y0761124*
X0879569Y07605*
X0879693Y0759876*
X0880046Y0759346*
X0880576Y0758993*
X08812Y0758869*
X0881824Y0758993*
X0882353Y0759346*
X0882707Y0759876*
X0882831Y07605*
X0882707Y0761124*
X0882353Y0761654*
X0881824Y0762007*
X08812Y0762131*
G37*
G36*
X09614Y0760731D02*
X0960776Y0760607D01*
X0960246Y0760253*
X0959893Y0759724*
X0959769Y07591*
X0959893Y0758476*
X0960246Y0757946*
X0960776Y0757593*
X09614Y0757469*
X0962024Y0757593*
X0962554Y0757946*
X0962907Y0758476*
X0963031Y07591*
X0962907Y0759724*
X0962554Y0760253*
X0962024Y0760607*
X09614Y0760731*
G37*
G36*
X0957Y0760631D02*
X0956376Y0760507D01*
X0955847Y0760153*
X0955493Y0759624*
X0955369Y0759*
X0955493Y0758376*
X0955847Y0757846*
X0956376Y0757493*
X0957Y0757369*
X0957624Y0757493*
X0958154Y0757846*
X0958507Y0758376*
X0958631Y0759*
X0958507Y0759624*
X0958154Y0760153*
X0957624Y0760507*
X0957Y0760631*
G37*
G36*
X1028878Y0764517D02*
X102769Y0764361D01*
X1026584Y0763902*
X1025633Y0763173*
X1024904Y0762223*
X1024445Y0761116*
X1024289Y0759928*
X1024445Y075874*
X1024904Y0757633*
X1025633Y0756683*
X1026584Y0755954*
X102769Y0755495*
X1028878Y0755339*
X1030066Y0755495*
X1031173Y0755954*
X1032123Y0756683*
X1032853Y0757633*
X1033311Y075874*
X1033467Y0759928*
X1033311Y0761116*
X1032853Y0762223*
X1032123Y0763173*
X1031173Y0763902*
X1030066Y0764361*
X1028878Y0764517*
G37*
G36*
X1017067D02*
X1015879Y0764361D01*
X1014773Y0763902*
X1013822Y0763173*
X1013093Y0762223*
X1012634Y0761116*
X1012478Y0759928*
X1012634Y075874*
X1013093Y0757633*
X1013822Y0756683*
X1014773Y0755954*
X1015879Y0755495*
X1017067Y0755339*
X1018255Y0755495*
X1019362Y0755954*
X1020312Y0756683*
X1021042Y0757633*
X10215Y075874*
X1021657Y0759928*
X10215Y0761116*
X1021042Y0762223*
X1020312Y0763173*
X1019362Y0763902*
X1018255Y0764361*
X1017067Y0764517*
G37*
G36*
X1005256D02*
X1004068Y0764361D01*
X1002962Y0763902*
X1002011Y0763173*
X1001282Y0762223*
X1000823Y0761116*
X1000667Y0759928*
X1000823Y075874*
X1001282Y0757633*
X1002011Y0756683*
X1002962Y0755954*
X1004068Y0755495*
X1005256Y0755339*
X1006444Y0755495*
X1007551Y0755954*
X1008501Y0756683*
X1009231Y0757633*
X1009689Y075874*
X1009845Y0759928*
X1009689Y0761116*
X1009231Y0762223*
X1008501Y0763173*
X1007551Y0763902*
X1006444Y0764361*
X1005256Y0764517*
G37*
G36*
X12275Y0752131D02*
X1226876Y0752007D01*
X1226346Y0751653*
X1225993Y0751124*
X1225869Y07505*
X1225993Y0749876*
X1226346Y0749346*
X1226876Y0748993*
X12275Y0748869*
X1228124Y0748993*
X1228654Y0749346*
X1229007Y0749876*
X1229131Y07505*
X1229007Y0751124*
X1228654Y0751653*
X1228124Y0752007*
X12275Y0752131*
G37*
G36*
X07011Y0750131D02*
X0700476Y0750007D01*
X0699946Y0749653*
X0699593Y0749124*
X0699469Y07485*
X0699593Y0747876*
X0699946Y0747346*
X0700476Y0746993*
X07011Y0746869*
X0701724Y0746993*
X0702253Y0747346*
X0702607Y0747876*
X0702731Y07485*
X0702607Y0749124*
X0702253Y0749653*
X0701724Y0750007*
X07011Y0750131*
G37*
G36*
X08615Y0748131D02*
X0860876Y0748007D01*
X0860347Y0747653*
X0859993Y0747124*
X0859869Y07465*
X0859993Y0745876*
X0860009Y0745851*
X0859649Y0745491*
X0859624Y0745507*
X0859Y0745631*
X0858376Y0745507*
X0857847Y0745154*
X0857493Y0744624*
X0857369Y0744*
X0857462Y0743531*
X0857414Y0743446*
X0857154Y0743186*
X0857069Y0743138*
X08566Y0743231*
X0855976Y0743107*
X0855447Y0742754*
X0855093Y0742224*
X0854969Y07416*
X0855093Y0740976*
X0855447Y0740447*
X0855976Y0740093*
X08566Y0739969*
X0857224Y0740093*
X0857753Y0740447*
X0858107Y0740976*
X0858231Y07416*
X0858138Y0742069*
X0858186Y0742154*
X0858446Y0742414*
X0858531Y0742462*
X0859Y0742369*
X0859624Y0742493*
X0860153Y0742846*
X0860507Y0743376*
X0860631Y0744*
X0860507Y0744624*
X0860491Y0744649*
X0860851Y0745009*
X0860876Y0744993*
X08615Y0744869*
X0862124Y0744993*
X0862654Y0745346*
X0863007Y0745876*
X0863131Y07465*
X0863007Y0747124*
X0862654Y0747653*
X0862124Y0748007*
X08615Y0748131*
G37*
G36*
X0826219Y0748412D02*
X0825595Y0748288D01*
X0825066Y0747934*
X0824712Y0747405*
X0824588Y0746781*
X0824712Y0746157*
X0825066Y0745627*
X0825595Y0745274*
X0826219Y074515*
X0826843Y0745274*
X0827372Y0745627*
X0827726Y0746157*
X082785Y0746781*
X0827726Y0747405*
X0827372Y0747934*
X0826843Y0748288*
X0826219Y0748412*
G37*
G36*
X08516Y0748331D02*
X0850976Y0748207D01*
X0850447Y0747854*
X0850093Y0747324*
X0849969Y07467*
X0850093Y0746076*
X0850447Y0745546*
X0850976Y0745193*
X08516Y0745069*
X0852224Y0745193*
X0852754Y0745546*
X0853107Y0746076*
X0853231Y07467*
X0853107Y0747324*
X0852754Y0747854*
X0852224Y0748207*
X08516Y0748331*
G37*
G36*
X1156831Y0753887D02*
X1155643Y0753731D01*
X1154536Y0753272*
X1153586Y0752543*
X1152857Y0751593*
X1152398Y0750486*
X1152242Y0749298*
X1152398Y074811*
X1152857Y0747003*
X1153586Y0746053*
X1154536Y0745324*
X1155643Y0744865*
X1156831Y0744709*
X1158019Y0744865*
X1159126Y0745324*
X1160076Y0746053*
X1160805Y0747003*
X1161264Y074811*
X116142Y0749298*
X1161264Y0750486*
X1160805Y0751593*
X1160076Y0752543*
X1159126Y0753272*
X1158019Y0753731*
X1156831Y0753887*
G37*
G36*
X08939Y0747631D02*
X0893276Y0747507D01*
X0892747Y0747154*
X0892393Y0746624*
X0892269Y0746*
X0892393Y0745376*
X0892747Y0744846*
X0893276Y0744493*
X08939Y0744369*
X0894524Y0744493*
X0895053Y0744846*
X0895407Y0745376*
X0895531Y0746*
X0895407Y0746624*
X0895053Y0747154*
X0894524Y0747507*
X08939Y0747631*
G37*
G36*
X0898069Y0746167D02*
X0897334Y0746021D01*
X0896711Y0745605*
X0896295Y0744982*
X0896149Y0744247*
X0896295Y0743512*
X0896711Y0742889*
X0897334Y0742473*
X0898069Y0742327*
X0898804Y0742473*
X0899427Y0742889*
X0899843Y0743512*
X0899989Y0744247*
X0899843Y0744982*
X0899427Y0745605*
X0898804Y0746021*
X0898069Y0746167*
G37*
G36*
X0819329D02*
X0818594Y0746021D01*
X0817971Y0745605*
X0817555Y0744982*
X0817409Y0744247*
X0817555Y0743512*
X0817971Y0742889*
X0818594Y0742473*
X0819329Y0742327*
X0820064Y0742473*
X0820687Y0742889*
X0821103Y0743512*
X0821249Y0744247*
X0821103Y0744982*
X0820687Y0745605*
X0820064Y0746021*
X0819329Y0746167*
G37*
G36*
X096081Y0755761D02*
X0959496Y0755631D01*
X0958232Y0755248*
X0957067Y0754625*
X0956046Y0753787*
X0955208Y0752766*
X0954585Y0751602*
X0954202Y0750338*
X0954072Y0749023*
X0954202Y0747709*
X0954585Y0746445*
X0955208Y074528*
X0956046Y0744259*
X0957067Y0743421*
X0958232Y0742798*
X0959496Y0742415*
X096081Y0742285*
X0962125Y0742415*
X0963389Y0742798*
X0964553Y0743421*
X0965574Y0744259*
X0966412Y074528*
X0967035Y0746445*
X0967418Y0747709*
X0967548Y0749023*
X0967418Y0750338*
X0967035Y0751602*
X0966412Y0752766*
X0965574Y0753787*
X0964553Y0754625*
X0963389Y0755248*
X0962125Y0755631*
X096081Y0755761*
G37*
G36*
X076421D02*
X0762895Y0755631D01*
X0761631Y0755248*
X0760467Y0754625*
X0759446Y0753787*
X0758608Y0752766*
X0757985Y0751602*
X0757601Y0750338*
X0757472Y0749023*
X0757601Y0747709*
X0757985Y0746445*
X0758608Y074528*
X0759446Y0744259*
X0760467Y0743421*
X0761631Y0742798*
X0762895Y0742415*
X076421Y0742285*
X0765524Y0742415*
X0766788Y0742798*
X0767953Y0743421*
X0768974Y0744259*
X0769812Y074528*
X0770435Y0746445*
X0770819Y0747709*
X0770948Y0749023*
X0770819Y0750338*
X0770435Y0751602*
X0769812Y0752766*
X0768974Y0753787*
X0767953Y0754625*
X0766788Y0755248*
X0765524Y0755631*
X076421Y0755761*
G37*
G36*
X0619Y0754931D02*
X0617745Y0754807D01*
X0616539Y0754441*
X0615427Y0753847*
X0614453Y0753047*
X0613653Y0752073*
X0613059Y0750961*
X0612693Y0749755*
X0612569Y07485*
X0612693Y0747245*
X0613059Y0746039*
X0613653Y0744927*
X0614453Y0743953*
X0615427Y0743153*
X0616539Y0742559*
X0617745Y0742193*
X0619Y0742069*
X0620255Y0742193*
X0621461Y0742559*
X0622573Y0743153*
X0623547Y0743953*
X0624347Y0744927*
X0624941Y0746039*
X0625307Y0747245*
X0625431Y07485*
X0625307Y0749755*
X0624941Y0750961*
X0624347Y0752073*
X0623547Y0753047*
X0622573Y0753847*
X0621461Y0754441*
X0620255Y0754807*
X0619Y0754931*
G37*
G36*
X08885Y0745131D02*
X0887876Y0745007D01*
X0887346Y0744654*
X0886993Y0744124*
X0886869Y07435*
X0886993Y0742876*
X0887346Y0742346*
X0887876Y0741993*
X08885Y0741869*
X0889124Y0741993*
X0889653Y0742346*
X0889746*
X0889946Y0742046*
X0890476Y0741693*
X08911Y0741569*
X0891724Y0741693*
X0892253Y0742046*
X0892607Y0742576*
X0892731Y07432*
X0892607Y0743824*
X0892253Y0744353*
X0891724Y0744707*
X08911Y0744831*
X0890476Y0744707*
X0889946Y0744353*
X0889854*
X0889653Y0744654*
X0889124Y0745007*
X08885Y0745131*
G37*
G36*
X1003Y0742631D02*
X1002376Y0742507D01*
X1001847Y0742154*
X1001493Y0741624*
X1001369Y0741*
X1001493Y0740376*
X1001847Y0739847*
X1002376Y0739493*
X1003Y0739369*
X1003624Y0739493*
X1004154Y0739847*
X1004507Y0740376*
X1004631Y0741*
X1004507Y0741624*
X1004154Y0742154*
X1003624Y0742507*
X1003Y0742631*
G37*
G36*
X09489Y0736131D02*
X0948276Y0736007D01*
X0947746Y0735653*
X0947393Y0735124*
X0947269Y07345*
X0947393Y0733876*
X0947746Y0733347*
X0948276Y0732993*
X09489Y0732869*
X0949524Y0732993*
X0950054Y0733347*
X0950407Y0733876*
X0950531Y07345*
X0950407Y0735124*
X0950054Y0735653*
X0949524Y0736007*
X09489Y0736131*
G37*
G36*
X08717Y0731331D02*
X0871076Y0731207D01*
X0870547Y0730854*
X0870333Y0730534*
X0869924Y0730807*
X08693Y0730931*
X0868676Y0730807*
X0868147Y0730453*
X0867793Y0729924*
X0867705Y0729485*
X0867231Y07295*
X0867107Y0730124*
X0866753Y0730653*
X0866224Y0731007*
X08656Y0731131*
X0864976Y0731007*
X0864447Y0730653*
X0864093Y0730124*
X0863969Y07295*
X086385Y0729382*
X08636Y0729431*
X0862976Y0729307*
X0862446Y0728954*
X0862093Y0728424*
X0861969Y07278*
X0862093Y0727176*
X0862446Y0726647*
X0862976Y0726293*
X08636Y0726169*
X0864224Y0726293*
X0864754Y0726647*
X0865107Y0727176*
X0865231Y07278*
X086535Y0727918*
X08656Y0727869*
X0866224Y0727993*
X0866753Y0728346*
X0867107Y0728876*
X0867195Y0729315*
X0867669Y07293*
X0867793Y0728676*
X0868147Y0728147*
X0868676Y0727793*
X08693Y0727669*
X0869924Y0727793*
X0870453Y0728147*
X0870667Y0728466*
X0871076Y0728193*
X08717Y0728069*
X0872324Y0728193*
X0872853Y0728546*
X0873207Y0729076*
X0873331Y07297*
X0873207Y0730324*
X0872853Y0730854*
X0872324Y0731207*
X08717Y0731331*
G37*
G36*
X08466Y0731131D02*
X0845976Y0731007D01*
X0845446Y0730653*
X0845093Y0730124*
X0844585Y0730135*
X08441Y0730231*
X0843476Y0730107*
X0842947Y0729753*
X0842593Y0729224*
X0842469Y07286*
X0842593Y0727976*
X0842947Y0727447*
X0843476Y0727093*
X08441Y0726969*
X0844724Y0727093*
X0845253Y0727447*
X0845607Y0727976*
X0846115Y0727965*
X08466Y0727869*
X0847224Y0727993*
X0847754Y0728346*
X0848107Y0728876*
X0848231Y07295*
X0848107Y0730124*
X0847754Y0730653*
X0847224Y0731007*
X08466Y0731131*
G37*
G36*
X08794Y0732731D02*
X0878776Y0732607D01*
X0878246Y0732254*
X0877893Y0731724*
X0877769Y07311*
X0877893Y0730476*
X0878246Y0729947*
X0878776Y0729593*
X08794Y0729469*
X0880024Y0729593*
X0880554Y0729947*
X0880907Y0730476*
X0881031Y07311*
X0880907Y0731724*
X0880554Y0732254*
X0880024Y0732607*
X08794Y0732731*
G37*
G36*
X08976Y0730731D02*
X0896976Y0730607D01*
X0896447Y0730254*
X0896093Y0729724*
X0895969Y07291*
X0896093Y0728476*
X0896447Y0727947*
X0896976Y0727593*
X08976Y0727469*
X0898224Y0727593*
X0898754Y0727947*
X0899107Y0728476*
X0899231Y07291*
X0899107Y0729724*
X0898754Y0730254*
X0898224Y0730607*
X08976Y0730731*
G37*
G36*
X08933Y0730631D02*
X0892676Y0730507D01*
X0892146Y0730154*
X0891793Y0729624*
X0891669Y0729*
X0891793Y0728376*
X0892146Y0727846*
X0892676Y0727493*
X08933Y0727369*
X0893924Y0727493*
X0894454Y0727846*
X0894807Y0728376*
X0894931Y0729*
X0894807Y0729624*
X0894454Y0730154*
X0893924Y0730507*
X08933Y0730631*
G37*
G36*
X084Y0733431D02*
X0839376Y0733307D01*
X0838846Y0732954*
X0838493Y0732424*
X0838369Y07318*
X0838493Y0731176*
X0838846Y0730647*
X083899Y0730551*
Y0729949*
X0838846Y0729853*
X0838493Y0729324*
X0838369Y07287*
X0838493Y0728076*
X0838846Y0727547*
X0839376Y0727193*
X084Y0727069*
X0840624Y0727193*
X0841154Y0727547*
X0841507Y0728076*
X0841631Y07287*
X0841507Y0729324*
X0841154Y0729853*
X084101Y0729949*
Y0730551*
X0841154Y0730647*
X0841507Y0731176*
X0841631Y07318*
X0841507Y0732424*
X0841154Y0732954*
X0840624Y0733307*
X084Y0733431*
G37*
G36*
X0857Y0730131D02*
X0856376Y0730007D01*
X0855847Y0729654*
X0855493Y0729124*
X0855369Y07285*
X0855493Y0727876*
X0855847Y0727347*
X0856376Y0726993*
X0857Y0726869*
X0857624Y0726993*
X0858154Y0727347*
X0858507Y0727876*
X0858631Y07285*
X0858507Y0729124*
X0858154Y0729654*
X0857624Y0730007*
X0857Y0730131*
G37*
G36*
X09333Y0728331D02*
X0932676Y0728207D01*
X0932146Y0727853*
X0931793Y0727324*
X0931669Y07267*
X0931793Y0726076*
X0932146Y0725547*
X0932676Y0725193*
X09333Y0725069*
X0933924Y0725193*
X0934453Y0725547*
X0934807Y0726076*
X0934931Y07267*
X0934807Y0727324*
X0934453Y0727853*
X0933924Y0728207*
X09333Y0728331*
G37*
G36*
X08832D02*
X0882576Y0728207D01*
X0882047Y0727853*
X0881693Y0727324*
X0881569Y07267*
X0881693Y0726076*
X0882047Y0725547*
X0882576Y0725193*
X08832Y0725069*
X0883824Y0725193*
X0884354Y0725547*
X0884707Y0726076*
X0884831Y07267*
X0884707Y0727324*
X0884354Y0727853*
X0883824Y0728207*
X08832Y0728331*
G37*
G36*
X11625Y0725631D02*
X1161876Y0725507D01*
X1161347Y0725153*
X1160993Y0724624*
X1160869Y0724*
X1160993Y0723376*
X1161347Y0722847*
X1161876Y0722493*
X11625Y0722369*
X1163124Y0722493*
X1163653Y0722847*
X1164007Y0723376*
X1164131Y0724*
X1164007Y0724624*
X1163653Y0725153*
X1163124Y0725507*
X11625Y0725631*
G37*
G36*
X0849D02*
X0848376Y0725507D01*
X0847847Y0725153*
X0847493Y0724624*
X0847369Y0724*
X0847493Y0723376*
X0847847Y0722847*
X0848376Y0722493*
X0849Y0722369*
X0849624Y0722493*
X0850154Y0722847*
X0850507Y0723376*
X0850631Y0724*
X0850507Y0724624*
X0850154Y0725153*
X0849624Y0725507*
X0849Y0725631*
G37*
G36*
X08321Y0723531D02*
X0831476Y0723407D01*
X0830947Y0723054*
X0830593Y0722524*
X0830469Y07219*
X0830593Y0721276*
X0830947Y0720747*
X0831476Y0720393*
X08321Y0720269*
X0832724Y0720393*
X0833253Y0720747*
X0833607Y0721276*
X0833731Y07219*
X0833607Y0722524*
X0833253Y0723054*
X0832724Y0723407*
X08321Y0723531*
G37*
G36*
X11568Y0723431D02*
X1156176Y0723307D01*
X1155647Y0722954*
X1155293Y0722424*
X1155169Y07218*
X1155293Y0721176*
X1155647Y0720646*
X1156176Y0720293*
X11568Y0720169*
X1157424Y0720293*
X1157953Y0720646*
X1158307Y0721176*
X1158431Y07218*
X1158307Y0722424*
X1157953Y0722954*
X1157424Y0723307*
X11568Y0723431*
G37*
G36*
X12415Y0720131D02*
X1240876Y0720007D01*
X1240347Y0719654*
X1239993Y0719124*
X1239869Y07185*
X1239993Y0717876*
X1240347Y0717346*
X1240876Y0716993*
X12415Y0716869*
X1242124Y0716993*
X1242653Y0717346*
X1243007Y0717876*
X1243131Y07185*
X1243007Y0719124*
X1242653Y0719654*
X1242124Y0720007*
X12415Y0720131*
G37*
G36*
X07745Y0714631D02*
X0773876Y0714507D01*
X0773347Y0714153*
X0772993Y0713624*
X0772869Y0713*
X0772993Y0712376*
X0773347Y0711846*
X0773876Y0711493*
X07745Y0711369*
X0775124Y0711493*
X0775654Y0711846*
X0776007Y0712376*
X0776131Y0713*
X0776007Y0713624*
X0775654Y0714153*
X0775124Y0714507*
X07745Y0714631*
G37*
G36*
X0761Y0714131D02*
X0760376Y0714007D01*
X0759846Y0713654*
X0759493Y0713124*
X0759369Y07125*
X0759493Y0711876*
X0759846Y0711346*
X0760376Y0710993*
X0761Y0710869*
X0761624Y0710993*
X0762153Y0711346*
X0762507Y0711876*
X0762631Y07125*
X0762507Y0713124*
X0762153Y0713654*
X0761624Y0714007*
X0761Y0714131*
G37*
G36*
X0768699Y0712037D02*
X0767964Y0711891D01*
X0767341Y0711475*
X0766925Y0710852*
X0766779Y0710117*
X0766925Y0709382*
X0767341Y0708759*
X0767964Y0708343*
X0768699Y0708197*
X0769434Y0708343*
X0770057Y0708759*
X0770473Y0709382*
X0770619Y0710117*
X0770473Y0710852*
X0770057Y0711475*
X0769434Y0711891*
X0768699Y0712037*
G37*
G36*
X07875Y0709131D02*
X0786876Y0709007D01*
X0786346Y0708653*
X0785993Y0708124*
X0785869Y07075*
X0785993Y0706876*
X0786346Y0706347*
X0786876Y0705993*
X07875Y0705869*
X0788124Y0705993*
X0788654Y0706347*
X0789007Y0706876*
X0789131Y07075*
X0789007Y0708124*
X0788654Y0708653*
X0788124Y0709007*
X07875Y0709131*
G37*
G36*
X0755836Y0708795D02*
X0755212Y0708671D01*
X0754682Y0708318*
X0754329Y0707788*
X0754205Y0707164*
X0754329Y070654*
X0754682Y070601*
X0755212Y0705657*
X0755836Y0705533*
X075646Y0705657*
X0756989Y070601*
X0757343Y070654*
X0757467Y0707164*
X0757343Y0707788*
X0756989Y0708318*
X075646Y0708671*
X0755836Y0708795*
G37*
G36*
X095619Y0712033D02*
X0955455Y0711887D01*
X0954832Y0711471*
X0954416Y0710848*
X095427Y0710113*
X0954416Y0709378*
X0954832Y0708755*
X0955455Y0708339*
X0955823Y0708266*
Y0707756*
X0955576Y0707707*
X0955046Y0707353*
X0954693Y0706824*
X0954569Y07062*
X0954693Y0705576*
X0954858Y0705329*
X0955008Y070495*
X0954858Y0704571*
X0954693Y0704324*
X0954569Y07037*
X0954693Y0703076*
X0955046Y0702547*
X0955576Y0702193*
X09562Y0702069*
X0956824Y0702193*
X0957353Y0702547*
X0957707Y0703076*
X0957831Y07037*
X0957707Y0704324*
X0957542Y0704571*
X0957392Y070495*
X0957542Y0705329*
X0957707Y0705576*
X0957831Y07062*
X0957707Y0706824*
X0957353Y0707353*
X0956824Y0707707*
X0956567Y0707758*
Y0708268*
X0956925Y0708339*
X0957548Y0708755*
X0957964Y0709378*
X095811Y0710113*
X0957964Y0710848*
X0957548Y0711471*
X0956925Y0711887*
X095619Y0712033*
G37*
G36*
X084Y0698731D02*
X0839376Y0698607D01*
X0838846Y0698253*
X0838493Y0697724*
X0838369Y06971*
X0838493Y0696476*
X083863Y0696271*
X0838269Y069591*
X0838124Y0696007*
X08375Y0696131*
X0836876Y0696007*
X0836347Y0695653*
X0835993Y0695124*
X0835869Y06945*
X0835993Y0693876*
X0836347Y0693347*
X0836876Y0692993*
X08375Y0692869*
X0838124Y0692993*
X0838653Y0693347*
X0839007Y0693876*
X0839131Y06945*
X0839007Y0695124*
X083887Y0695329*
X0839231Y069569*
X0839376Y0695593*
X084Y0695469*
X0840624Y0695593*
X0841154Y0695947*
X0841507Y0696476*
X0841631Y06971*
X0841507Y0697724*
X0841154Y0698253*
X0840624Y0698607*
X084Y0698731*
G37*
G36*
X09289Y0699131D02*
X0928276Y0699007D01*
X0927746Y0698654*
X0927393Y0698124*
X0927269Y06975*
X0927393Y0696876*
X0927746Y0696347*
X0928276Y0695993*
X09289Y0695869*
X0929524Y0695993*
X0930054Y0696347*
X0930407Y0696876*
X0930531Y06975*
X0930407Y0698124*
X0930054Y0698654*
X0929524Y0699007*
X09289Y0699131*
G37*
G36*
X07Y0697631D02*
X0699376Y0697507D01*
X0698846Y0697154*
X0698493Y0696624*
X0698369Y0696*
X0698493Y0695376*
X0698846Y0694846*
X0699376Y0694493*
X07Y0694369*
X0700624Y0694493*
X0701154Y0694846*
X0701507Y0695376*
X0701631Y0696*
X0701507Y0696624*
X0701154Y0697154*
X0700624Y0697507*
X07Y0697631*
G37*
G36*
X0829Y0693631D02*
X0828376Y0693507D01*
X0827847Y0693153*
X0827493Y0692624*
X0827369Y0692*
X0827493Y0691376*
X0827847Y0690846*
X0828376Y0690493*
X0829Y0690369*
X0829624Y0690493*
X0830153Y0690846*
X0830507Y0691376*
X0830631Y0692*
X0830507Y0692624*
X0830153Y0693153*
X0829624Y0693507*
X0829Y0693631*
G37*
G36*
X0619Y0702431D02*
X0617745Y0702307D01*
X0616539Y0701941*
X0615427Y0701347*
X0614453Y0700547*
X0613653Y0699573*
X0613059Y0698461*
X0612693Y0697255*
X0612569Y0696*
X0612693Y0694745*
X0613059Y0693539*
X0613653Y0692427*
X0614453Y0691453*
X0615427Y0690653*
X0616539Y0690059*
X0617745Y0689693*
X0619Y0689569*
X0620255Y0689693*
X0621461Y0690059*
X0622573Y0690653*
X0623547Y0691453*
X0624347Y0692427*
X0624941Y0693539*
X0625307Y0694745*
X0625431Y0696*
X0625307Y0697255*
X0624941Y0698461*
X0624347Y0699573*
X0623547Y0700547*
X0622573Y0701347*
X0621461Y0701941*
X0620255Y0702307*
X0619Y0702431*
G37*
G36*
X09545Y0691131D02*
X0953876Y0691007D01*
X0953347Y0690654*
X0952993Y0690124*
X0952869Y06895*
X0952993Y0688876*
X0953347Y0688346*
X0953876Y0687993*
X09545Y0687869*
X0955124Y0687993*
X0955653Y0688346*
X0956007Y0688876*
X0956131Y06895*
X0956007Y0690124*
X0955653Y0690654*
X0955124Y0691007*
X09545Y0691131*
G37*
G36*
X09383Y0689131D02*
X0937676Y0689007D01*
X0937146Y0688654*
X0936793Y0688124*
X0936669Y06875*
X0936793Y0686876*
X0937146Y0686346*
X0937676Y0685993*
X09383Y0685869*
X0938924Y0685993*
X0939454Y0686346*
X0939807Y0686876*
X0939931Y06875*
X0939807Y0688124*
X0939454Y0688654*
X0938924Y0689007*
X09383Y0689131*
G37*
G36*
X0942941Y0689119D02*
X0942317Y0688995D01*
X0941787Y0688641*
X0941434Y0688112*
X094131Y0687488*
X0941434Y0686863*
X0941787Y0686334*
X0942317Y068598*
X0942941Y0685856*
X0943565Y068598*
X0944094Y0686334*
X0944448Y0686863*
X0944572Y0687488*
X0944448Y0688112*
X0944094Y0688641*
X0943565Y0688995*
X0942941Y0689119*
G37*
G36*
X09795Y0686031D02*
X0978876Y0685907D01*
X0978347Y0685554*
X0977993Y0685024*
X0977869Y06844*
X0977993Y0683776*
X0978347Y0683247*
X0978876Y0682893*
X09795Y0682769*
X0980124Y0682893*
X0980653Y0683247*
X0981007Y0683776*
X0981131Y06844*
X0981007Y0685024*
X0980653Y0685554*
X0980124Y0685907*
X09795Y0686031*
G37*
G36*
X0931933Y0684631D02*
X0931309Y0684507D01*
X0930779Y0684154*
X0930426Y0683624*
X0930302Y0683*
X0930426Y0682376*
X0930779Y0681847*
X0931309Y0681493*
X0931933Y0681369*
X0932557Y0681493*
X0933086Y0681847*
X093344Y0682376*
X0933564Y0683*
X093344Y0683624*
X0933086Y0684154*
X0932557Y0684507*
X0931933Y0684631*
G37*
G36*
X09935Y0683631D02*
X0992876Y0683507D01*
X0992346Y0683153*
X0991993Y0682624*
X0991869Y0682*
X0991993Y0681376*
X0992346Y0680847*
X0992876Y0680493*
X09935Y0680369*
X0994124Y0680493*
X0994654Y0680847*
X0995007Y0681376*
X0995131Y0682*
X0995007Y0682624*
X0994654Y0683153*
X0994124Y0683507*
X09935Y0683631*
G37*
G36*
X0787009Y0683205D02*
X0786385Y0683081D01*
X0785856Y0682727*
X0785502Y0682198*
X0785378Y0681574*
X0785502Y068095*
X0785856Y068042*
X0786385Y0680067*
X0787009Y0679943*
X0787634Y0680067*
X0788163Y068042*
X0788517Y068095*
X0788641Y0681574*
X0788517Y0682198*
X0788163Y0682727*
X0787634Y0683081*
X0787009Y0683205*
G37*
G36*
X09268Y0682531D02*
X0926176Y0682407D01*
X0925646Y0682054*
X0925293Y0681524*
X0925169Y06809*
X0925293Y0680276*
X0925646Y0679746*
X0926176Y0679393*
X09268Y0679269*
X0927424Y0679393*
X0927954Y0679746*
X0928307Y0680276*
X0928431Y06809*
X0928307Y0681524*
X0927954Y0682054*
X0927424Y0682407*
X09268Y0682531*
G37*
G36*
X10055Y0681631D02*
X1004876Y0681507D01*
X1004346Y0681153*
X1003993Y0680624*
X1003869Y068*
X1003993Y0679376*
X1004346Y0678847*
X1004876Y0678493*
X10055Y0678369*
X1006124Y0678493*
X1006653Y0678847*
X1007007Y0679376*
X1007131Y068*
X1007007Y0680624*
X1006653Y0681153*
X1006124Y0681507*
X10055Y0681631*
G37*
G36*
X0857Y0681031D02*
X0856376Y0680907D01*
X0855847Y0680553*
X0855493Y0680024*
X0855369Y06794*
X0855493Y0678776*
X0855847Y0678246*
X0856376Y0677893*
X0857Y0677769*
X0857624Y0677893*
X0858154Y0678246*
X0858507Y0678776*
X0858631Y06794*
X0858507Y0680024*
X0858154Y0680553*
X0857624Y0680907*
X0857Y0681031*
G37*
G36*
X08617Y0679031D02*
X0861076Y0678907D01*
X0860546Y0678553*
X0860193Y0678024*
X0860069Y06774*
X0860193Y0676776*
X0860546Y0676247*
X0861076Y0675893*
X08617Y0675769*
X0862324Y0675893*
X0862854Y0676247*
X0863207Y0676776*
X0863331Y06774*
X0863207Y0678024*
X0862854Y0678553*
X0862324Y0678907*
X08617Y0679031*
G37*
G36*
X0971Y0678631D02*
X0970376Y0678507D01*
X0969847Y0678154*
X0969493Y0677624*
X0969369Y0677*
X0969493Y0676376*
X0969847Y0675846*
X0970376Y0675493*
X0971Y0675369*
X0971624Y0675493*
X0972153Y0675846*
X0972507Y0676376*
X0972631Y0677*
X0972507Y0677624*
X0972153Y0678154*
X0971624Y0678507*
X0971Y0678631*
G37*
G36*
X0854Y0677531D02*
X0853376Y0677407D01*
X0852847Y0677053*
X0852493Y0676524*
X0852369Y06759*
X0852493Y0675276*
X0852847Y0674747*
X0853376Y0674393*
X0854Y0674269*
X0854624Y0674393*
X0855153Y0674747*
X0855507Y0675276*
X0855631Y06759*
X0855507Y0676524*
X0855153Y0677053*
X0854624Y0677407*
X0854Y0677531*
G37*
G36*
X10125Y0677131D02*
X1011876Y0677007D01*
X1011347Y0676653*
X1010993Y0676124*
X1010869Y06755*
X1010993Y0674876*
X1011347Y0674346*
X1011876Y0673993*
X10125Y0673869*
X1013124Y0673993*
X1013653Y0674346*
X1014007Y0674876*
X1014131Y06755*
X1014007Y0676124*
X1013653Y0676653*
X1013124Y0677007*
X10125Y0677131*
G37*
G36*
X08595Y0675431D02*
X0858876Y0675307D01*
X0858346Y0674954*
X0857993Y0674424*
X0857869Y06738*
X0857993Y0673176*
X0858346Y0672647*
X0858876Y0672293*
X08595Y0672169*
X0860124Y0672293*
X0860653Y0672647*
X0861007Y0673176*
X0861131Y06738*
X0861007Y0674424*
X0860653Y0674954*
X0860124Y0675307*
X08595Y0675431*
G37*
G36*
X0918742Y0673431D02*
X0918118Y0673307D01*
X0917589Y0672954*
X0917235Y0672424*
X0917111Y06718*
X0917235Y0671176*
X0917589Y0670646*
X0918118Y0670293*
X0918742Y0670169*
X0919366Y0670293*
X0919896Y0670646*
X0920249Y0671176*
X0920373Y06718*
X0920249Y0672424*
X0919896Y0672954*
X0919366Y0673307*
X0918742Y0673431*
G37*
G36*
X0958Y0673131D02*
X0957376Y0673007D01*
X0956847Y0672653*
X0956493Y0672124*
X0956369Y06715*
X0956493Y0670876*
X0956847Y0670346*
X0957376Y0669993*
X0958Y0669869*
X0958624Y0669993*
X0959153Y0670346*
X0959507Y0670876*
X0959631Y06715*
X0959507Y0672124*
X0959153Y0672653*
X0958624Y0673007*
X0958Y0673131*
G37*
G36*
X07884Y0671331D02*
X0787776Y0671207D01*
X0787247Y0670854*
X0786893Y0670324*
X0786769Y06697*
X0786893Y0669076*
X0787247Y0668546*
X0787776Y0668193*
X07884Y0668069*
X0789024Y0668193*
X0789553Y0668546*
X0789907Y0669076*
X0790031Y06697*
X0789907Y0670324*
X0789553Y0670854*
X0789024Y0671207*
X07884Y0671331*
G37*
G36*
X09794Y0671131D02*
X0978776Y0671007D01*
X0978246Y0670653*
X0977893Y0670124*
X0977769Y06695*
X0977893Y0668876*
X0978246Y0668347*
X0978776Y0667993*
X09794Y0667869*
X0980024Y0667993*
X0980554Y0668347*
X0980907Y0668876*
X0981031Y06695*
X0980907Y0670124*
X0980554Y0670653*
X0980024Y0671007*
X09794Y0671131*
G37*
G36*
X09715Y0669531D02*
X0970876Y0669407D01*
X0970347Y0669054*
X0969993Y0668524*
X0969869Y06679*
X0969993Y0667276*
X0970347Y0666747*
X0970876Y0666393*
X09715Y0666269*
X0972124Y0666393*
X0972653Y0666747*
X0973007Y0667276*
X0973131Y06679*
X0973007Y0668524*
X0972653Y0669054*
X0972124Y0669407*
X09715Y0669531*
G37*
G36*
X0781294Y0669425D02*
X078067Y0669301D01*
X078014Y0668948*
X0779787Y0668418*
X0779663Y0667794*
X0779787Y066717*
X078014Y0666641*
X078067Y0666287*
X0781294Y0666163*
X0781918Y0666287*
X0782447Y0666641*
X0782801Y066717*
X0782925Y0667794*
X0782801Y0668418*
X0782447Y0668948*
X0781918Y0669301*
X0781294Y0669425*
G37*
G36*
X0976402Y0668635D02*
X0975778Y0668511D01*
X0975249Y0668157*
X0974895Y0667628*
X0974771Y0667004*
X0974895Y066638*
X0975249Y066585*
X0975778Y0665497*
X0976402Y0665373*
X0977026Y0665497*
X0977556Y066585*
X0977909Y066638*
X0978033Y0667004*
X0977909Y0667628*
X0977556Y0668157*
X0977026Y0668511*
X0976402Y0668635*
G37*
G36*
X12835Y0668131D02*
X1282876Y0668007D01*
X1282347Y0667654*
X1281993Y0667124*
X1281869Y06665*
X1281993Y0665876*
X1282347Y0665346*
X1282876Y0664993*
X12835Y0664869*
X1284124Y0664993*
X1284653Y0665346*
X1285007Y0665876*
X1285131Y06665*
X1285007Y0667124*
X1284653Y0667654*
X1284124Y0668007*
X12835Y0668131*
G37*
G36*
X09215Y066816D02*
X0920876Y0668036D01*
X0920347Y0667682*
X0919993Y0667153*
X0919869Y0666528*
X0919993Y0665904*
X0920347Y0665375*
X0920876Y0665021*
X09215Y0664897*
X0922124Y0665021*
X0922565Y0665316*
X0922974Y0665364*
X0923208Y0665305*
X0923676Y0664993*
X09243Y0664869*
X0924924Y0664993*
X0925453Y0665346*
X0925807Y0665876*
X0925931Y06665*
X0925807Y0667124*
X0925453Y0667654*
X0924924Y0668007*
X09243Y0668131*
X0923676Y0668007*
X0923234Y0667712*
X0922826Y0667665*
X0922592Y0667723*
X0922124Y0668036*
X09215Y066816*
G37*
G36*
X08657Y0666031D02*
X0865076Y0665907D01*
X0864546Y0665554*
X0864193Y0665024*
X0864069Y06644*
X0864153Y0663977*
X0863807Y066358*
X0863765Y0663559*
X08634Y0663631*
X0862776Y0663507*
X0862247Y0663154*
X0861893Y0662624*
X0861769Y0662*
X0861893Y0661376*
X0862247Y0660847*
X0862776Y0660493*
X08634Y0660369*
X0864024Y0660493*
X0864554Y0660847*
X0864907Y0661376*
X0865031Y0662*
X0864947Y0662423*
X0865293Y066282*
X0865335Y0662841*
X08657Y0662769*
X0866324Y0662893*
X0866854Y0663246*
X0867207Y0663776*
X0867331Y06644*
X0867207Y0665024*
X0866854Y0665554*
X0866324Y0665907*
X08657Y0666031*
G37*
G36*
X10125Y0667131D02*
X1011876Y0667007D01*
X1011347Y0666653*
X1010993Y0666124*
X1010869Y06655*
X1010993Y0664876*
X1011347Y0664347*
X1011876Y0663993*
X101238Y0663893*
X1012592Y066356*
X1012644Y0663387*
X1012639Y066338*
X1012515Y0662756*
X1012639Y0662132*
X1012993Y0661602*
X1013522Y0661249*
X1014146Y0661125*
X1014771Y0661249*
X1015139Y0661495*
X10155Y0661135*
X1015493Y0661124*
X1015369Y06605*
X1015493Y0659876*
X1015847Y0659346*
X1016376Y0658993*
X1017Y0658869*
X1017624Y0658993*
X1018153Y0659346*
X1018507Y0659876*
X1018631Y06605*
X1018507Y0661124*
X1018153Y0661654*
X1017624Y0662007*
X1017Y0662131*
X1016376Y0662007*
X1016007Y0661761*
X1015647Y0662121*
X1015654Y0662132*
X1015778Y0662756*
X1015654Y066338*
X10153Y066391*
X1014771Y0664263*
X1014266Y0664363*
X1014054Y0664696*
X1014002Y0664868*
X1014007Y0664876*
X1014131Y06655*
X1014007Y0666124*
X1013653Y0666653*
X1013124Y0667007*
X10125Y0667131*
G37*
G36*
X0871Y0661131D02*
X0870376Y0661007D01*
X0869847Y0660653*
X0869493Y0660124*
X0869369Y06595*
X0869493Y0658876*
X0869847Y0658347*
X0870376Y0657993*
X0871Y0657869*
X0871624Y0657993*
X0872153Y0658347*
X0872507Y0658876*
X0872631Y06595*
X0872507Y0660124*
X0872153Y0660653*
X0871624Y0661007*
X0871Y0661131*
G37*
G36*
X09885Y0658631D02*
X0987876Y0658507D01*
X0987346Y0658153*
X0986993Y0657624*
X0986869Y0657*
X0986993Y0656376*
X0987346Y0655847*
X0987876Y0655493*
X09885Y0655369*
X0989124Y0655493*
X0989653Y0655847*
X0990007Y0656376*
X0990131Y0657*
X0990007Y0657624*
X0989653Y0658153*
X0989124Y0658507*
X09885Y0658631*
G37*
G36*
X0996Y0657231D02*
X0995376Y0657107D01*
X0994847Y0656753*
X0994493Y0656224*
X0994369Y06556*
X0994493Y0654976*
X0994847Y0654447*
X0995376Y0654093*
X0996Y0653969*
X0996624Y0654093*
X0996825Y0654227*
X0997327Y0654342*
X0997583Y0654189*
X0997876Y0653993*
X09985Y0653869*
X0999124Y0653993*
X0999654Y0654347*
X1000007Y0654876*
X1000131Y06555*
X1000007Y0656124*
X0999654Y0656653*
X0999124Y0657007*
X09985Y0657131*
X0997876Y0657007*
X0997346Y0656653*
X099722*
X0997153Y0656753*
X0996624Y0657107*
X0996Y0657231*
G37*
G36*
X10025Y0656631D02*
X1001876Y0656507D01*
X1001346Y0656153*
X1000993Y0655624*
X1000869Y0655*
X1000993Y0654376*
X1001346Y0653847*
X1001876Y0653493*
X10025Y0653369*
X1003124Y0653493*
X1003654Y0653847*
X1004007Y0654376*
X1004131Y0655*
X1004007Y0655624*
X1003654Y0656153*
X1003124Y0656507*
X10025Y0656631*
G37*
G36*
X09915Y0655631D02*
X0990876Y0655507D01*
X0990347Y0655154*
X0989993Y0654624*
X0989869Y0654*
X0989993Y0653376*
X0990347Y0652846*
X0990876Y0652493*
X09915Y0652369*
X0992124Y0652493*
X0992653Y0652846*
X0993007Y0653376*
X0993131Y0654*
X0993007Y0654624*
X0992653Y0655154*
X0992124Y0655507*
X09915Y0655631*
G37*
G36*
X08885Y0658131D02*
X0887876Y0658007D01*
X0887346Y0657654*
X0886993Y0657124*
X0886869Y06565*
X0886993Y0655876*
X0887346Y0655346*
X0887876Y0654993*
X08885Y0654869*
X0889124Y0654993*
X0889149Y0655009*
X0889509Y0654649*
X0889493Y0654624*
X0889369Y0654*
X0889493Y0653376*
X0889847Y0652846*
X0890376Y0652493*
X0891Y0652369*
X0891624Y0652493*
X0892153Y0652846*
X0892507Y0653376*
X0892631Y0654*
X0892507Y0654624*
X0892153Y0655154*
X0891624Y0655507*
X0891Y0655631*
X0890376Y0655507*
X0890351Y0655491*
X0889991Y0655851*
X0890007Y0655876*
X0890131Y06565*
X0890007Y0657124*
X0889653Y0657654*
X0889124Y0658007*
X08885Y0658131*
G37*
G36*
X0771Y0655631D02*
X0770376Y0655507D01*
X0769846Y0655154*
X0769493Y0654624*
X0769369Y0654*
X0769493Y0653376*
X0769846Y0652846*
X0770376Y0652493*
X0771Y0652369*
X0771624Y0652493*
X0772154Y0652846*
X0772507Y0653376*
X0772631Y0654*
X0772507Y0654624*
X0772154Y0655154*
X0771624Y0655507*
X0771Y0655631*
G37*
G36*
X0788746Y0653677D02*
X0788122Y0653553D01*
X0787593Y0653199*
X0787239Y065267*
X0787115Y0652046*
X0787239Y0651422*
X0787593Y0650892*
X0788122Y0650539*
X0788746Y0650415*
X078937Y0650539*
X0789899Y0650892*
X0790253Y0651422*
X0790377Y0652046*
X0790253Y065267*
X0789899Y0653199*
X078937Y0653553*
X0788746Y0653677*
G37*
G36*
X10055Y0653131D02*
X1004876Y0653007D01*
X1004346Y0652654*
X1003993Y0652124*
X1003869Y06515*
X1003993Y0650876*
X1004346Y0650347*
X1004876Y0649993*
X10055Y0649869*
X1006124Y0649993*
X1006653Y0650347*
X1007007Y0650876*
X1007131Y06515*
X1007007Y0652124*
X1006653Y0652654*
X1006124Y0653007*
X10055Y0653131*
G37*
G36*
X09855D02*
X0984876Y0653007D01*
X0984346Y0652654*
X0983993Y0652124*
X0983869Y06515*
X0983993Y0650876*
X0984346Y0650347*
X0984876Y0649993*
X09855Y0649869*
X0986124Y0649993*
X0986654Y0650347*
X0987007Y0650876*
X0987131Y06515*
X0987007Y0652124*
X0986654Y0652654*
X0986124Y0653007*
X09855Y0653131*
G37*
G36*
X08265Y0652631D02*
X0825876Y0652507D01*
X0825346Y0652153*
X0824993Y0651624*
X0824869Y0651*
X0824993Y0650376*
X0825346Y0649847*
X0825876Y0649493*
X08265Y0649369*
X0827124Y0649493*
X0827654Y0649847*
X0828007Y0650376*
X0828131Y0651*
X0828007Y0651624*
X0827654Y0652153*
X0827124Y0652507*
X08265Y0652631*
G37*
G36*
X09825Y0650131D02*
X0981876Y0650007D01*
X0981347Y0649653*
X0980993Y0649124*
X0980869Y06485*
X0980993Y0647876*
X0981347Y0647346*
X0981876Y0646993*
X09825Y0646869*
X0983124Y0646993*
X0983654Y0647346*
X0984007Y0647876*
X0984131Y06485*
X0984007Y0649124*
X0983654Y0649653*
X0983124Y0650007*
X09825Y0650131*
G37*
G36*
X08685D02*
X0867876Y0650007D01*
X0867346Y0649653*
X0866993Y0649124*
X0866869Y06485*
X0866993Y0647876*
X0867346Y0647346*
X0867876Y0646993*
X08685Y0646869*
X0869124Y0646993*
X0869654Y0647346*
X0870007Y0647876*
X0870131Y06485*
X0870007Y0649124*
X0869654Y0649653*
X0869124Y0650007*
X08685Y0650131*
G37*
G36*
X0954Y0646131D02*
X0953376Y0646007D01*
X0952847Y0645653*
X0952493Y0645124*
X0952369Y06445*
X0952493Y0643876*
X0952847Y0643347*
X0953376Y0642993*
X0954Y0642869*
X0954624Y0642993*
X0955153Y0643347*
X0955507Y0643876*
X0955631Y06445*
X0955507Y0645124*
X0955153Y0645653*
X0954624Y0646007*
X0954Y0646131*
G37*
G36*
X08437Y0645731D02*
X0843076Y0645607D01*
X0842546Y0645254*
X0842193Y0644724*
X0842069Y06441*
X0842193Y0643476*
X0842546Y0642946*
X0843076Y0642593*
X08437Y0642469*
X0844324Y0642593*
X0844853Y0642946*
X0845207Y0643476*
X0845331Y06441*
X0845207Y0644724*
X0844853Y0645254*
X0844324Y0645607*
X08437Y0645731*
G37*
G36*
X06999Y0645031D02*
X0699276Y0644907D01*
X0698746Y0644554*
X0698393Y0644024*
X0698269Y06434*
X0698393Y0642776*
X0698746Y0642246*
X0699276Y0641893*
X06999Y0641769*
X0700524Y0641893*
X0701053Y0642246*
X0701407Y0642776*
X0701531Y06434*
X0701407Y0644024*
X0701053Y0644554*
X0700524Y0644907*
X06999Y0645031*
G37*
G36*
X08074Y0643191D02*
X0806776Y0643067D01*
X0806246Y0642713*
X0805893Y0642184*
X0805769Y064156*
X0805893Y0640936*
X0805901Y0640923*
X0805708Y0640633*
X0805571Y0640518*
X0805Y0640631*
X0804376Y0640507*
X0803846Y0640154*
X0803493Y0639624*
X0803369Y0639*
X0803493Y0638376*
X0803846Y0637847*
X0804376Y0637493*
X0805Y0637369*
X0805624Y0637493*
X0806153Y0637847*
X0806507Y0638376*
X0806631Y0639*
X0806507Y0639624*
X0806499Y0639637*
X0806692Y0639927*
X0806829Y0640042*
X08074Y0639929*
X0808024Y0640053*
X0808554Y0640407*
X0808907Y0640936*
X0809031Y064156*
X0808907Y0642184*
X0808554Y0642713*
X0808024Y0643067*
X08074Y0643191*
G37*
G36*
X0939744Y0643157D02*
X093912Y0643033D01*
X093859Y064268*
X0938237Y064215*
X0938113Y0641526*
X0938237Y0640902*
X0938536Y0640453*
X0938153Y0640154*
X0937624Y0640507*
X0937Y0640631*
X0936376Y0640507*
X0935847Y0640154*
X0935493Y0639624*
X0935369Y0639*
X0935493Y0638376*
X0935847Y0637847*
X0936376Y0637493*
X0937Y0637369*
X0937518Y0637472*
X0937822Y0637254*
X0937944Y0637105*
X0937869Y0636726*
X0937993Y0636102*
X0938218Y0635764*
X0938282Y0635669*
X0937921Y0635309*
X0937844Y063536*
X0937624Y0635507*
X0937Y0635631*
X0936376Y0635507*
X0935847Y0635153*
X0935493Y0634624*
X0935369Y0634*
X0935493Y0633376*
X0935847Y0632846*
X0936376Y0632493*
X0937Y0632369*
X0937624Y0632493*
X0938153Y0632846*
X0938507Y0633376*
X0938631Y0634*
X0938507Y0634624*
X0938282Y0634962*
X0938218Y0635057*
X0938579Y0635417*
X0938656Y0635366*
X0938876Y0635219*
X09395Y0635095*
X0940124Y0635219*
X0940654Y0635572*
X0941007Y0636102*
X0941131Y0636726*
X0941007Y063735*
X0940654Y063788*
X0940124Y0638233*
X09395Y0638357*
X0938982Y0638254*
X0938678Y0638472*
X0938556Y0638621*
X0938631Y0639*
X0938507Y0639624*
X0938208Y0640073*
X093859Y0640372*
X093912Y0640019*
X0939744Y0639895*
X0940368Y0640019*
X0940897Y0640373*
X0941251Y0640902*
X0941375Y0641526*
X0941251Y064215*
X0940897Y064268*
X0940368Y0643033*
X0939744Y0643157*
G37*
G36*
X0619Y0649931D02*
X0617745Y0649807D01*
X0616539Y0649441*
X0615427Y0648847*
X0614453Y0648047*
X0613653Y0647073*
X0613059Y0645961*
X0612693Y0644755*
X0612569Y06435*
X0612693Y0642245*
X0613059Y0641039*
X0613653Y0639927*
X0614453Y0638953*
X0615427Y0638153*
X0616539Y0637559*
X0617745Y0637193*
X0619Y0637069*
X0620255Y0637193*
X0621461Y0637559*
X0622573Y0638153*
X0623547Y0638953*
X0624347Y0639927*
X0624941Y0641039*
X0625307Y0642245*
X0625431Y06435*
X0625307Y0644755*
X0624941Y0645961*
X0624347Y0647073*
X0623547Y0648047*
X0622573Y0648847*
X0621461Y0649441*
X0620255Y0649807*
X0619Y0649931*
G37*
G36*
X08019Y0638191D02*
X0801276Y0638067D01*
X0800747Y0637713*
X0800393Y0637184*
X0800269Y063656*
X0800393Y0635936*
X0800401Y0635923*
X0800208Y0635633*
X0800071Y0635518*
X07995Y0635631*
X0798876Y0635507*
X0798347Y0635153*
X0797993Y0634624*
X0797869Y0634*
X0797993Y0633376*
X0798347Y0632846*
X0798876Y0632493*
X07995Y0632369*
X0800124Y0632493*
X0800653Y0632846*
X0801007Y0633376*
X0801131Y0634*
X0801007Y0634624*
X0800999Y0634637*
X0801192Y0634927*
X0801329Y0635042*
X08019Y0634929*
X0802524Y0635053*
X0803053Y0635406*
X0803407Y0635936*
X0803531Y063656*
X0803407Y0637184*
X0803053Y0637713*
X0802524Y0638067*
X08019Y0638191*
G37*
G36*
X07556Y0633931D02*
X0754976Y0633807D01*
X0754447Y0633454*
X0754093Y0632924*
X0753969Y06323*
X0754093Y0631676*
X0754447Y0631146*
X0754976Y0630793*
X07556Y0630669*
X0756224Y0630793*
X0756753Y0631146*
X0757107Y0631676*
X0757231Y06323*
X0757107Y0632924*
X0756753Y0633454*
X0756224Y0633807*
X07556Y0633931*
G37*
G36*
X08493Y0633631D02*
X0848676Y0633507D01*
X0848147Y0633153*
X0847793Y0632624*
X0847669Y0632*
X0847793Y0631376*
X0848147Y0630847*
X0848676Y0630493*
X08493Y0630369*
X0849924Y0630493*
X0850453Y0630847*
X0850807Y0631376*
X0850931Y0632*
X0850807Y0632624*
X0850453Y0633153*
X0849924Y0633507*
X08493Y0633631*
G37*
G36*
X0768699Y0633297D02*
X0767964Y0633151D01*
X0767341Y0632735*
X0766925Y0632112*
X0766779Y0631377*
X0766925Y0630642*
X0767341Y0630019*
X0767964Y0629603*
X0768699Y0629457*
X0769434Y0629603*
X0770057Y0630019*
X0770473Y0630642*
X0770619Y0631377*
X0770473Y0632112*
X0770057Y0632735*
X0769434Y0633151*
X0768699Y0633297*
G37*
G36*
X095619Y0633293D02*
X0955455Y0633147D01*
X0954832Y0632731*
X0954416Y0632108*
X095427Y0631373*
X0954416Y0630638*
X0954832Y0630015*
X0955455Y0629599*
X095619Y0629453*
X0956925Y0629599*
X0957548Y0630015*
X0957964Y0630638*
X095811Y0631373*
X0957964Y0632108*
X0957548Y0632731*
X0956925Y0633147*
X095619Y0633293*
G37*
G36*
X08197Y0631831D02*
X0819076Y0631707D01*
X0818546Y0631354*
X0818193Y0630824*
X0818069Y06302*
X0818193Y0629576*
X0818546Y0629046*
X0819076Y0628693*
X08197Y0628569*
X0820324Y0628693*
X0820854Y0629046*
X0821207Y0629576*
X0821331Y06302*
X0821207Y0630824*
X0820854Y0631354*
X0820324Y0631707*
X08197Y0631831*
G37*
G36*
X07782Y0631731D02*
X0777576Y0631607D01*
X0777046Y0631253*
X0776693Y0630724*
X0776569Y06301*
X0776693Y0629476*
X0777046Y0628946*
X0777576Y0628593*
X07782Y0628469*
X0778824Y0628593*
X0779354Y0628946*
X0779707Y0629476*
X0779831Y06301*
X0779707Y0630724*
X0779354Y0631253*
X0778824Y0631607*
X07782Y0631731*
G37*
G36*
X08692Y0600131D02*
X0868576Y0600007D01*
X0868046Y0599653*
X0867778Y0599251*
X0867671Y0599223*
X0867329*
X0867222Y0599251*
X0866953Y0599653*
X0866424Y0600007*
X08658Y0600131*
X0865176Y0600007*
X0864647Y0599653*
X0864293Y0599124*
X0864169Y05985*
X0863707Y0598424*
X0863354Y0598953*
X0862824Y0599307*
X08622Y0599431*
X0861576Y0599307*
X0861047Y0598953*
X0860804Y059859*
X0860602Y0598564*
X0860261Y0598599*
X0860256Y0598601*
X0859953Y0599053*
X0859424Y0599407*
X08588Y0599531*
X0858176Y0599407*
X0857646Y0599053*
X0857293Y0598524*
X0857169Y05979*
X0857293Y0597276*
X0857646Y0596746*
X0858176Y0596393*
X08588Y0596269*
X0859424Y0596393*
X0859953Y0596746*
X0860196Y059711*
X0860398Y0597136*
X0860739Y0597101*
X0860744Y0597099*
X0861047Y0596646*
X0861576Y0596293*
X08622Y0596169*
X0862824Y0596293*
X0863354Y0596646*
X0863707Y0597176*
X0863831Y05978*
X0864293Y0597876*
X0864647Y0597346*
X0865176Y0596993*
X08658Y0596869*
X0866424Y0596993*
X0866953Y0597346*
X0867222Y0597749*
X0867329Y0597777*
X0867671*
X0867778Y0597749*
X0868046Y0597346*
X0868439Y0597084*
X0868501Y0596638*
X0868474Y0596505*
X0868246Y0596353*
X0867893Y0595824*
X0867769Y05952*
X0867893Y0594576*
X0868246Y0594046*
X0868776Y0593693*
X08694Y0593569*
X0870024Y0593693*
X0870553Y0594046*
X0870658Y0594203*
X0871189Y0594097*
X0871193Y0594076*
X0871546Y0593546*
X0872076Y0593193*
X08727Y0593069*
X0873324Y0593193*
X0873853Y0593546*
X0874207Y0594076*
X0874331Y05947*
X0874207Y0595324*
X0873853Y0595854*
X0873324Y0596207*
X08727Y0596331*
X0872076Y0596207*
X0871546Y0595854*
X0871442Y0595697*
X0870911Y0595803*
X0870907Y0595824*
X0870553Y0596353*
X087016Y0596616*
X0870098Y0597062*
X0870126Y0597195*
X0870354Y0597346*
X0870707Y0597876*
X0870831Y05985*
X0870707Y0599124*
X0870354Y0599653*
X0869824Y0600007*
X08692Y0600131*
G37*
G36*
X0873525Y0600808D02*
X0872901Y0600684D01*
X0872372Y0600331*
X0872018Y0599801*
X0871894Y0599177*
X0872018Y0598553*
X0872372Y0598024*
X0872901Y059767*
X0873525Y0597546*
X087415Y059767*
X0874434Y059786*
X0874986Y0597652*
X0875025Y0597457*
X0875378Y0596928*
X0875908Y0596574*
X0876532Y059645*
X0877156Y0596574*
X0877685Y0596928*
X0877953Y0597328*
X0878473Y0597273*
X0878493Y0597176*
X0878846Y0596646*
X0879376Y0596293*
X088Y0596169*
X0880624Y0596293*
X0881153Y0596646*
X0881507Y0597176*
X0881577Y0597527*
X0882108Y0597774*
X0882317Y0597634*
X0882941Y059751*
X0883565Y0597634*
X0884095Y0597987*
X0884448Y0598517*
X0884572Y0599141*
X0884448Y0599765*
X0884095Y0600294*
X0883565Y0600648*
X0882941Y0600772*
X0882317Y0600648*
X0881787Y0600294*
X0881434Y0599765*
X0881364Y0599414*
X0880833Y0599167*
X0880624Y0599307*
X088Y0599431*
X0879376Y0599307*
X0878846Y0598953*
X0878579Y0598553*
X0878058Y0598608*
X0878039Y0598705*
X0877685Y0599235*
X0877156Y0599588*
X0876532Y0599713*
X0875908Y0599588*
X0875622Y0599398*
X0875071Y0599607*
X0875033Y0599801*
X0874679Y0600331*
X087415Y0600684*
X0873525Y0600808*
G37*
G36*
X089807Y0598173D02*
X0897335Y0598027D01*
X0896712Y0597611*
X0896296Y0596988*
X089615Y0596253*
X0896296Y0595518*
X0896712Y0594895*
X0897335Y0594479*
X089807Y0594333*
X0898805Y0594479*
X0899428Y0594895*
X0899844Y0595518*
X089999Y0596253*
X0899844Y0596988*
X0899428Y0597611*
X0898805Y0598027*
X089807Y0598173*
G37*
G36*
X081933D02*
X0818595Y0598027D01*
X0817972Y0597611*
X0817556Y0596988*
X081741Y0596253*
X0817556Y0595518*
X0817972Y0594895*
X0818595Y0594479*
X081933Y0594333*
X0820065Y0594479*
X0820688Y0594895*
X0821104Y0595518*
X082125Y0596253*
X0821104Y0596988*
X0820688Y0597611*
X0820065Y0598027*
X081933Y0598173*
G37*
G36*
X08469Y0595731D02*
X0846276Y0595607D01*
X0845747Y0595254*
X0845393Y0594724*
X0845269Y05941*
X0845393Y0593476*
X0845747Y0592946*
X0846276Y0592593*
X08469Y0592469*
X0847524Y0592593*
X0848053Y0592946*
X0848407Y0593476*
X0848531Y05941*
X0848407Y0594724*
X0848053Y0595254*
X0847524Y0595607*
X08469Y0595731*
G37*
G36*
X06995Y0592631D02*
X0698876Y0592507D01*
X0698347Y0592154*
X0697993Y0591624*
X0697869Y0591*
X0697993Y0590376*
X0698347Y0589847*
X0698876Y0589493*
X06995Y0589369*
X0700124Y0589493*
X0700654Y0589847*
X0701007Y0590376*
X0701131Y0591*
X0701007Y0591624*
X0700654Y0592154*
X0700124Y0592507*
X06995Y0592631*
G37*
G36*
X096081Y0598761D02*
X0959496Y0598631D01*
X0958232Y0598248*
X0957067Y0597625*
X0956046Y0596787*
X0955208Y0595766*
X0954585Y0594601*
X0954202Y0593337*
X0954072Y0592023*
X0954202Y0590708*
X0954585Y0589444*
X0955208Y058828*
X0956046Y0587259*
X0957067Y0586421*
X0958232Y0585798*
X0959496Y0585415*
X096081Y0585285*
X0962125Y0585415*
X0963389Y0585798*
X0964553Y0586421*
X0965574Y0587259*
X0966412Y058828*
X0967035Y0589444*
X0967418Y0590708*
X0967548Y0592023*
X0967418Y0593337*
X0967035Y0594601*
X0966412Y0595766*
X0965574Y0596787*
X0964553Y0597625*
X0963389Y0598248*
X0962125Y0598631*
X096081Y0598761*
G37*
G36*
X076431D02*
X0762995Y0598631D01*
X0761731Y0598248*
X0760567Y0597625*
X0759546Y0596787*
X0758708Y0595766*
X0758085Y0594601*
X0757701Y0593337*
X0757572Y0592023*
X0757701Y0590708*
X0758085Y0589444*
X0758708Y058828*
X0759546Y0587259*
X0760567Y0586421*
X0761731Y0585798*
X0762995Y0585415*
X076431Y0585285*
X0765625Y0585415*
X0766889Y0585798*
X0768053Y0586421*
X0769074Y0587259*
X0769912Y058828*
X0770535Y0589444*
X0770919Y0590708*
X0771048Y0592023*
X0770919Y0593337*
X0770535Y0594601*
X0769912Y0595766*
X0769074Y0596787*
X0768053Y0597625*
X0766889Y0598248*
X0765625Y0598631*
X076431Y0598761*
G37*
G36*
X1156831Y0594045D02*
X1155643Y0593888D01*
X1154536Y059343*
X1153586Y0592701*
X1152857Y059175*
X1152398Y0590643*
X1152242Y0589456*
X1152398Y0588268*
X1152857Y0587161*
X1153586Y058621*
X1154536Y0585481*
X1155643Y0585023*
X1156831Y0584866*
X1158019Y0585023*
X1159126Y0585481*
X1160076Y058621*
X1160805Y0587161*
X1161264Y0588268*
X116142Y0589456*
X1161264Y0590643*
X1160805Y059175*
X1160076Y0592701*
X1159126Y059343*
X1158019Y0593888*
X1156831Y0594045*
G37*
G36*
X0996988D02*
X0995801Y0593888D01*
X0994694Y059343*
X0993743Y0592701*
X0993014Y059175*
X0992556Y0590643*
X0992399Y0589456*
X0992556Y0588268*
X0993014Y0587161*
X0993743Y058621*
X0994694Y0585481*
X0995801Y0585023*
X0996988Y0584866*
X0998176Y0585023*
X0999283Y0585481*
X1000234Y058621*
X1000963Y0587161*
X1001421Y0588268*
X1001578Y0589456*
X1001421Y0590643*
X1000963Y059175*
X1000234Y0592701*
X0999283Y059343*
X0998176Y0593888*
X0996988Y0594045*
G37*
G36*
X0619Y0597431D02*
X0617745Y0597307D01*
X0616539Y0596941*
X0615427Y0596347*
X0614453Y0595547*
X0613653Y0594573*
X0613059Y0593461*
X0612693Y0592255*
X0612569Y0591*
X0612693Y0589745*
X0613059Y0588539*
X0613653Y0587427*
X0614453Y0586453*
X0615427Y0585653*
X0616539Y0585059*
X0617745Y0584693*
X0619Y0584569*
X0620255Y0584693*
X0621461Y0585059*
X0622573Y0585653*
X0623547Y0586453*
X0624347Y0587427*
X0624941Y0588539*
X0625307Y0589745*
X0625431Y0591*
X0625307Y0592255*
X0624941Y0593461*
X0624347Y0594573*
X0623547Y0595547*
X0622573Y0596347*
X0621461Y0596941*
X0620255Y0597307*
X0619Y0597431*
G37*
G36*
X0888285Y0584882D02*
X0887661Y0584758D01*
X0887131Y0584405*
X0886778Y0583875*
X0886769Y0583832*
X0886648Y0583751*
X0886221Y0583642*
X0885824Y0583907*
X08852Y0584031*
X0884576Y0583907*
X0884046Y0583554*
X0883693Y0583024*
X0883569Y05824*
X0883693Y0581776*
X0884046Y0581247*
X0884576Y0580893*
X08852Y0580769*
X0885824Y0580893*
X0886353Y0581247*
X0886707Y0581776*
X0886716Y0581819*
X0886836Y05819*
X0887263Y0582009*
X0887661Y0581744*
X0888285Y058162*
X0888909Y0581744*
X0889438Y0582097*
X0889792Y0582627*
X0889916Y0583251*
X0889792Y0583875*
X0889438Y0584405*
X0888909Y0584758*
X0888285Y0584882*
G37*
G36*
X08616Y0583331D02*
X0860976Y0583207D01*
X0860446Y0582854*
X0860178Y0582451*
X0860071Y0582423*
X0859729*
X0859622Y0582451*
X0859354Y0582854*
X0858824Y0583207*
X08582Y0583331*
X0857576Y0583207*
X0857047Y0582854*
X0856693Y0582324*
X0856569Y05817*
X0856693Y0581076*
X0857047Y0580547*
X0857576Y0580193*
X08582Y0580069*
X0858824Y0580193*
X0859354Y0580547*
X0859622Y0580949*
X0859729Y0580977*
X0860071*
X0860178Y0580949*
X0860446Y0580547*
X0860976Y0580193*
X08616Y0580069*
X0862224Y0580193*
X0862753Y0580547*
X0863107Y0581076*
X0863231Y05817*
X0863107Y0582324*
X0862753Y0582854*
X0862224Y0583207*
X08616Y0583331*
G37*
G36*
X08822Y0580831D02*
X0881576Y0580707D01*
X0881046Y0580353*
X0880693Y0579824*
X0880569Y05792*
X0880693Y0578576*
X0881046Y0578047*
X0881576Y0577693*
X08822Y0577569*
X0882824Y0577693*
X0883354Y0578047*
X0883707Y0578576*
X0883831Y05792*
X0883707Y0579824*
X0883354Y0580353*
X0882824Y0580707*
X08822Y0580831*
G37*
G36*
X08734Y0584331D02*
X0872776Y0584207D01*
X0872246Y0583853*
X0871893Y0583324*
X0871769Y05827*
X0871893Y0582076*
X0872246Y0581546*
X0872776Y0581193*
X08734Y0581069*
X0874024Y0581193*
X0874553Y0581546*
X0874567Y0581567*
X0874729Y058159*
X087514Y0581524*
X0875416Y0581109*
X0875946Y0580756*
X087657Y0580631*
X0877016Y058072*
X0877194Y0580756*
X0877405Y0580327*
X0877147Y0580154*
X0876793Y0579624*
X0876669Y0579*
X0876793Y0578376*
X0877147Y0577846*
X0877676Y0577493*
X08783Y0577369*
X0878924Y0577493*
X0879453Y0577846*
X0879807Y0578376*
X0879931Y0579*
X0879807Y0579624*
X0879453Y0580154*
X0878924Y0580507*
X08783Y0580631*
X0877854Y0580543*
X0877676Y0580507*
X0877464Y0580936*
X0877724Y0581109*
X0878077Y0581638*
X0878201Y0582263*
X0878077Y0582887*
X0877724Y0583416*
X0877194Y058377*
X087657Y0583894*
X0875946Y058377*
X0875416Y0583416*
X0875403Y0583396*
X0875241Y0583372*
X087483Y0583439*
X0874553Y0583853*
X0874024Y0584207*
X08734Y0584331*
G37*
G36*
X13206Y0583441D02*
X1318513Y0583277D01*
X1316477Y0582788*
X1314543Y0581987*
X1312758Y0580893*
X1311166Y0579534*
X1309807Y0577942*
X1308713Y0576157*
X1307912Y0574223*
X1307423Y0572187*
X1307259Y05701*
X1307423Y0568013*
X1307912Y0565977*
X1308713Y0564043*
X1309807Y0562258*
X1311166Y0560666*
X1312758Y0559307*
X1314543Y0558213*
X1316477Y0557412*
X1318513Y0556923*
X13206Y0556759*
X1322687Y0556923*
X1324723Y0557412*
X1326657Y0558213*
X1328442Y0559307*
X1330034Y0560666*
X1331393Y0562258*
X1332487Y0564043*
X1333288Y0565977*
X1333777Y0568013*
X1333941Y05701*
X1333777Y0572187*
X1333288Y0574223*
X1332487Y0576157*
X1331393Y0577942*
X1330034Y0579534*
X1328442Y0580893*
X1326657Y0581987*
X1324723Y0582788*
X1322687Y0583277*
X13206Y0583441*
G37*
G36*
X08369Y0545031D02*
X0836276Y0544907D01*
X0836098Y0544788*
X08357Y0544578*
X0835302Y0544788*
X0835124Y0544907*
X08345Y0545031*
X0833876Y0544907*
X0833346Y0544554*
X0832993Y0544024*
X0832869Y05434*
X0832993Y0542776*
X0833346Y0542246*
X0833876Y0541893*
X08345Y0541769*
X0835124Y0541893*
X0835302Y0542012*
X08357Y0542222*
X0836098Y0542012*
X0836276Y0541893*
X08369Y0541769*
X0837524Y0541893*
X0838054Y0542246*
X0838407Y0542776*
X0838531Y05434*
X0838407Y0544024*
X0838054Y0544554*
X0837524Y0544907*
X08369Y0545031*
G37*
G36*
X08845Y0541531D02*
X0883876Y0541407D01*
X0883346Y0541053*
X0883011Y0540552*
X0882798Y0540524*
X0882702*
X0882489Y0540552*
X0882154Y0541053*
X0881624Y0541407*
X0881Y0541531*
X0880376Y0541407*
X0879846Y0541053*
X0879493Y0540524*
X0879369Y05399*
X0879493Y0539276*
X0879846Y0538747*
X0880376Y0538393*
X0881Y0538269*
X0881624Y0538393*
X0882154Y0538747*
X0882489Y0539248*
X0882702Y0539276*
X0882798*
X0883011Y0539248*
X0883346Y0538747*
X0883876Y0538393*
X08845Y0538269*
X0885124Y0538393*
X0885653Y0538747*
X0886007Y0539276*
X0886131Y05399*
X0886007Y0540524*
X0885653Y0541053*
X0885124Y0541407*
X08845Y0541531*
G37*
G36*
X0846Y0541831D02*
X0845376Y0541707D01*
X0844847Y0541354*
X0844493Y0540824*
X0844369Y05402*
X0844493Y0539576*
X0844847Y0539046*
X0845376Y0538693*
X0846Y0538569*
X0846624Y0538693*
X0847153Y0539046*
X0847507Y0539576*
X0847631Y05402*
X0847507Y0540824*
X0847153Y0541354*
X0846624Y0541707*
X0846Y0541831*
G37*
G36*
X08655Y0541731D02*
X0864876Y0541607D01*
X0864347Y0541254*
X0863993Y0540724*
X0863869Y05401*
X0863993Y0539476*
X0864347Y0538946*
X0864876Y0538593*
X08655Y0538469*
X0866124Y0538593*
X0866654Y0538946*
X0867007Y0539476*
X0867131Y05401*
X0867007Y0540724*
X0866654Y0541254*
X0866124Y0541607*
X08655Y0541731*
G37*
G36*
X08502D02*
X0849576Y0541607D01*
X0849047Y0541254*
X0848693Y0540724*
X0848569Y05401*
X0848693Y0539476*
X0849047Y0538946*
X0849576Y0538593*
X08502Y0538469*
X0850824Y0538593*
X0851353Y0538946*
X0851707Y0539476*
X0851831Y05401*
X0851707Y0540724*
X0851353Y0541254*
X0850824Y0541607*
X08502Y0541731*
G37*
G36*
X0901Y0541631D02*
X0900376Y0541507D01*
X0899846Y0541153*
X0899493Y0540624*
X0899369Y054*
X0899493Y0539376*
X0899846Y0538846*
X0900376Y0538493*
X0901Y0538369*
X0901624Y0538493*
X0902153Y0538846*
X0902507Y0539376*
X0902631Y054*
X0902507Y0540624*
X0902153Y0541153*
X0901624Y0541507*
X0901Y0541631*
G37*
G36*
X08695D02*
X0868876Y0541507D01*
X0868347Y0541153*
X0867993Y0540624*
X0867869Y054*
X0867993Y0539376*
X0868347Y0538846*
X0868876Y0538493*
X08695Y0538369*
X0870124Y0538493*
X0870654Y0538846*
X0871007Y0539376*
X0871131Y054*
X0871007Y0540624*
X0870654Y0541153*
X0870124Y0541507*
X08695Y0541631*
G37*
G36*
X0897Y0541431D02*
X0896376Y0541307D01*
X0895846Y0540953*
X0895493Y0540424*
X0895369Y05398*
X0895493Y0539176*
X0895846Y0538647*
X0896376Y0538293*
X0897Y0538169*
X0897624Y0538293*
X0898153Y0538647*
X0898507Y0539176*
X0898631Y05398*
X0898507Y0540424*
X0898153Y0540953*
X0897624Y0541307*
X0897Y0541431*
G37*
G36*
X0786221Y0530765D02*
X0785596Y0530641D01*
X0785236Y0530401*
X0784876Y0530641*
X0784252Y0530765*
X0783628Y0530641*
X0783268Y0530401*
X0782908Y0530641*
X0782283Y0530765*
X0781659Y0530641*
X078113Y0530287*
X0780776Y0529758*
X0780652Y0529134*
X0780776Y052851*
X078113Y052798*
X078131Y052786*
Y0527258*
X078113Y0527138*
X0780776Y0526609*
X0780652Y0525984*
X0780776Y052536*
X078113Y0524831*
X0781659Y0524477*
X0782283Y0524353*
X0782908Y0524477*
X0783268Y0524718*
X0783628Y0524477*
X0784252Y0524353*
X0784876Y0524477*
X0785236Y0524718*
X0785596Y0524477*
X0786221Y0524353*
X0786845Y0524477*
X0787374Y0524831*
X0787728Y052536*
X0787852Y0525984*
X0787728Y0526609*
X0787374Y0527138*
X0787193Y0527258*
Y052786*
X0787374Y052798*
X0787728Y052851*
X0787852Y0529134*
X0787728Y0529758*
X0787374Y0530287*
X0786845Y0530641*
X0786221Y0530765*
G37*
G36*
X0876Y0530631D02*
X0875376Y0530507D01*
X0875198Y0530388*
X08748Y0530178*
X0874402Y0530388*
X0874224Y0530507*
X08736Y0530631*
X0872976Y0530507*
X0872447Y0530154*
X0872093Y0529624*
X0871969Y0529*
X0872093Y0528376*
X0872447Y0527846*
X0872976Y0527493*
X08736Y0527369*
X0874224Y0527493*
X0874402Y0527612*
X08748Y0527822*
X0875198Y0527612*
X0875376Y0527493*
X0876Y0527369*
X0876624Y0527493*
X0877153Y0527846*
X0877507Y0528376*
X0877631Y0529*
X0877507Y0529624*
X0877153Y0530154*
X0876624Y0530507*
X0876Y0530631*
G37*
G36*
X08922Y0530331D02*
X0891576Y0530207D01*
X0891398Y0530088*
X0891Y0529878*
X0890602Y0530088*
X0890424Y0530207*
X08898Y0530331*
X0889176Y0530207*
X0888647Y0529853*
X0888293Y0529324*
X0888169Y05287*
X0888293Y0528076*
X0888647Y0527547*
X0889176Y0527193*
X08898Y0527069*
X0890424Y0527193*
X0890602Y0527312*
X0891Y0527522*
X0891398Y0527312*
X0891576Y0527193*
X08922Y0527069*
X0892824Y0527193*
X0893353Y0527547*
X0893707Y0528076*
X0893831Y05287*
X0893707Y0529324*
X0893353Y0529853*
X0892824Y0530207*
X08922Y0530331*
G37*
G36*
X0810236Y0530765D02*
X0809612Y0530641D01*
X0809083Y0530287*
X0808729Y0529758*
X080872Y052971*
X080821*
X08082Y0529758*
X0807847Y0530287*
X0807317Y0530641*
X0806693Y0530765*
X0806069Y0530641*
X0805539Y0530287*
X0805186Y0529758*
X0805062Y0529134*
X0805186Y052851*
X0805539Y052798*
X080572Y052786*
Y0527258*
X0805539Y0527138*
X0805186Y0526609*
X0805062Y0525984*
X0805186Y052536*
X0805539Y0524831*
X0806069Y0524477*
X0806693Y0524353*
X0807317Y0524477*
X0807847Y0524831*
X08082Y052536*
X080821Y0525408*
X080872*
X0808729Y052536*
X0809083Y0524831*
X0809612Y0524477*
X0810236Y0524353*
X0810861Y0524477*
X081139Y0524831*
X0811743Y052536*
X0811868Y0525984*
X0811743Y0526609*
X081139Y0527138*
X0811209Y0527258*
Y052786*
X081139Y052798*
X0811743Y052851*
X0811868Y0529134*
X0811743Y0529758*
X081139Y0530287*
X0810861Y0530641*
X0810236Y0530765*
G37*
G36*
X08422Y0530131D02*
X0841576Y0530007D01*
X0841398Y0529888*
X0841Y0529678*
X0840602Y0529888*
X0840424Y0530007*
X08398Y0530131*
X0839176Y0530007*
X0838647Y0529654*
X0838293Y0529124*
X0838169Y05285*
X0838293Y0527876*
X0838647Y0527347*
X0839176Y0526993*
X08398Y0526869*
X0840424Y0526993*
X0840602Y0527112*
X0841Y0527322*
X0841398Y0527112*
X0841576Y0526993*
X08422Y0526869*
X0842824Y0526993*
X0843353Y0527347*
X0843707Y0527876*
X0843831Y05285*
X0843707Y0529124*
X0843353Y0529654*
X0842824Y0530007*
X08422Y0530131*
G37*
G36*
X08566Y0530531D02*
X0855976Y0530407D01*
X0855447Y0530054*
X0855093Y0529524*
X0854969Y05289*
X0855093Y0528276*
X0855447Y0527746*
X0855976Y0527393*
X08566Y0527269*
X0857224Y0527393*
X0857701Y0527712*
X085788Y0527766*
X0858267*
X0858346Y0527646*
X0858876Y0527293*
X08595Y0527169*
X0860124Y0527293*
X0860653Y0527646*
X0861007Y0528176*
X0861131Y05288*
X0861007Y0529424*
X0860653Y0529953*
X0860124Y0530307*
X08595Y0530431*
X0858876Y0530307*
X0858399Y0529988*
X085822Y0529934*
X0857833*
X0857753Y0530054*
X0857224Y0530407*
X08566Y0530531*
G37*
G36*
X0814173Y0530765D02*
X0813549Y0530641D01*
X081302Y0530287*
X0812666Y0529758*
X0812542Y0529134*
X0812666Y052851*
X081302Y052798*
X08132Y052786*
Y0527258*
X081302Y0527138*
X0812666Y0526609*
X0812542Y0525984*
X0812666Y052536*
X081302Y0524831*
X0813549Y0524477*
X0814173Y0524353*
X0814797Y0524477*
X0815327Y0524831*
X081568Y052536*
X0815805Y0525984*
X081568Y0526609*
X0815327Y0527138*
X0815146Y0527258*
Y052786*
X0815327Y052798*
X081568Y052851*
X0815805Y0529134*
X081568Y0529758*
X0815327Y0530287*
X0814797Y0530641*
X0814173Y0530765*
G37*
G36*
X06285Y0550641D02*
X0626413Y0550477D01*
X0624377Y0549988*
X0622443Y0549187*
X0620658Y0548093*
X0619066Y0546734*
X0617707Y0545142*
X0616613Y0543357*
X0615812Y0541423*
X0615323Y0539387*
X0615159Y05373*
X0615323Y0535213*
X0615812Y0533177*
X0616613Y0531243*
X0617707Y0529458*
X0619066Y0527866*
X0620658Y0526507*
X0622443Y0525413*
X0624377Y0524612*
X0626413Y0524123*
X06285Y0523959*
X0630587Y0524123*
X0632623Y0524612*
X0634557Y0525413*
X0636342Y0526507*
X0637934Y0527866*
X0639293Y0529458*
X0640387Y0531243*
X0641188Y0533177*
X0641677Y0535213*
X0641841Y05373*
X0641677Y0539387*
X0641188Y0541423*
X0640387Y0543357*
X0639293Y0545142*
X0637934Y0546734*
X0636342Y0548093*
X0634557Y0549187*
X0632623Y0549988*
X0630587Y0550477*
X06285Y0550641*
G37*
%LNgrandmaster-3*%
%LPD*%
G54D140*
X0609Y0601D03*
Y0581D03*
X0629D03*
Y0601D03*
X0609Y07585D03*
Y07385D03*
X0629D03*
Y07585D03*
X0609Y0706D03*
Y0686D03*
X0629D03*
Y0706D03*
X0609Y06535D03*
Y06335D03*
X0629D03*
Y06535D03*
G54D155*
X0996988Y0749298D03*
X1156831Y0669377D03*
G54D156*
X1255965Y0859346D03*
X12725Y0881D03*
X1289035Y0859346D03*
G54D158*
X1211Y0906D03*
G54D159*
X1192496Y0894189D03*
G54D165*
X090876Y0524705D03*
X0894587Y0525591D03*
X0853622Y0524878D03*
X0843701Y0525D03*
X079063Y052487D03*
X08025Y0525D03*
X0862703Y0525184D03*
X0878937Y0525591D03*
X083Y0525D03*
X0887205Y0525689D03*
X0891732Y0814961D03*
X0885827D03*
X0883071D03*
X0888976D03*
X0891732Y0811811D03*
X0885827D03*
X0883071D03*
X0888976D03*
X0891732Y081811D03*
X0885827D03*
X0883071D03*
X0888976D03*
Y082126D03*
X0883071D03*
X0885827D03*
X0891732D03*
X1224409Y0791339D03*
X126378Y0813386D03*
X1033Y07729D03*
X0940462Y06809D03*
X07779Y09331D03*
X09581Y06666D03*
X08774Y07572D03*
X07712Y06993D03*
X08887Y08382D03*
X08505Y05941D03*
X08656Y06096D03*
X09821Y08766D03*
X08314Y0759D03*
X07662Y06796D03*
X08774Y06098D03*
X09386Y09226D03*
X10263Y08139D03*
X0971Y07D03*
X09401Y0671759D03*
X07705Y06599D03*
X1085Y08D03*
X0813Y08742D03*
X08479Y07417D03*
X08401Y06093D03*
X1012Y0852D03*
X0903536Y0821364D03*
X10199Y08139D03*
X09585Y06518D03*
X08676Y07572D03*
X07662Y06403D03*
X12617Y08036D03*
X10143Y08139D03*
X10055Y07726D03*
X08715Y08525D03*
X08302Y05938D03*
X08862Y07301D03*
X07666Y06895D03*
X07239Y07004D03*
X0971Y06925D03*
X09404Y06577D03*
X07712Y06698D03*
X08807Y07907D03*
X08907D03*
X10122Y0669D03*
X08303Y06097D03*
X10059Y08139D03*
X08665Y08505D03*
X10225Y07729D03*
X08714Y07924D03*
X08395Y07416D03*
X09723Y06422D03*
X08577Y07573D03*
X07662Y06501D03*
X09545Y06995D03*
X08961Y08415D03*
X12447Y08013D03*
X07682Y09083D03*
X09633Y0564D03*
X08774Y07433D03*
X07665Y06993D03*
X1003Y08788D03*
X12467Y08235D03*
X10324Y08139D03*
X10468D03*
X09545Y06845D03*
X09397Y06465D03*
X07707Y06403D03*
X07709Y06796D03*
X09188Y08218D03*
X07717Y0933D03*
X08244Y07283D03*
X08924Y05957D03*
X08466Y0746D03*
X07661Y06599D03*
X08892Y06099D03*
X09545Y06945D03*
X09959Y06675D03*
X09951Y07728D03*
X08601Y05938D03*
X08464Y07984D03*
X08676Y07315D03*
X08597Y06095D03*
X07252Y07486D03*
X09709Y06717D03*
X0954Y06417D03*
X08872Y0757D03*
X07709Y06501D03*
X07712Y06894D03*
X08875Y07903D03*
X09987Y06715D03*
X08404Y08299D03*
X10105Y08139D03*
X12639Y08345D03*
X0832Y08365D03*
X08622Y0788D03*
X08879Y09225D03*
X09361Y07892D03*
X084Y07583D03*
X07661Y06698D03*
X08833Y06099D03*
X08753Y07906D03*
X08249Y08745D03*
X08406Y07796D03*
X08572Y07312D03*
X08499Y06094D03*
X0774Y09114D03*
X08281Y09221D03*
X09871Y08113D03*
X09735Y08346D03*
X09708Y08076D03*
X11724Y0856D03*
X11667Y0855D03*
X08405Y05941D03*
X09594Y05686D03*
X08715Y06097D03*
X12619Y06376D03*
X12539Y06535D03*
X12593Y06616D03*
Y06676D03*
Y06726D03*
X12592Y06781D03*
X12676Y06832D03*
X1269Y06885D03*
X13042Y06961D03*
X1294Y07099D03*
X12598Y0718D03*
X12386Y07115D03*
X12039Y07175D03*
X11995Y07438D03*
X12265Y07395D03*
X12389Y07457D03*
X12388Y07505D03*
X12387Y0756D03*
X12388Y07614D03*
X12389Y07661D03*
X123622Y0791339D03*
X10901Y09207D03*
X10378Y0921D03*
X09768Y09027D03*
X10076Y08896D03*
X10185Y08888D03*
X10422Y08139D03*
X09321Y08305D03*
X0909Y07916D03*
X09023Y07972D03*
X09009Y07901D03*
X08851Y08791D03*
X08715Y08733D03*
X09522Y08664D03*
X0926Y08792D03*
X07233Y06476D03*
X07247Y05946D03*
X06645Y05794D03*
X06646Y06032D03*
X06645Y06318D03*
X06644Y06555D03*
X06645Y06843D03*
Y07077D03*
Y07369D03*
X0664412Y0759783D03*
M02*